FILE_TYPE=PINLIST;
{ Packager-XL run on 25-Aug-2023 AT 17:03:33 }
TIME=' COMPILATION ON 25-Aug-2023 AT 17:03:33';
primitive '2N7002A7-2N7002A-7,SMLF,IC,BAMA';body '2N7002A7';
    'G':'(G)';IN;
    'D':'(D)';BIDI;
    'S':'(S)';BIDI;
end_primitive;
primitive '74HC1G126GW-74HC1G126GW,SMLF,IA';body '74HC1G126GW';
    '2':'(2)';IN;
    '4':'(4)';OUT;
    '5':'(5)';
    '1':'(1)';IN;
    'GND':'(3)';
end_primitive;
primitive '74LVC1G07GW-74LVC1G07GW,SMLF,EA';body '74LVC1G07GW';
    'VCC':'(5)';
    'A':'(2)';IN;
    'GND':'(3)';
    'Y':'(4)';OUT;
    'NC':'(1)';OUT;
end_primitive;
primitive '74LVC1G07GW-74LVC1G07GW,SMLF,IA';body '74LVC1G07GW';
    'VCC':'(5)';
    'A':'(2)';IN;
    'GND':'(3)';
    'Y':'(4)';OUT;
    'NC':'(1)';OUT;
end_primitive;
primitive '74LVC1G07W57-74LVC1G07W5-7,SMLA';body '74LVC1G07W57';
    'VCC':'(5)';
    'A':'(2)';IN;
    'GND':'(3)';
    'Y':'(4)';OUT;
    'NC1':'(1)';OUT;
end_primitive;
primitive '74LVC1G08GW_SM-74LVC1G08GW,IC,A';body '74LVC1G08GW';
    'B':'(1)';BIDI;
    'A':'(2)';BIDI;
    'Y':'(4)';BIDI;
    'VCC':'(5)';
    'GND':'(3)';
end_primitive;
primitive '74LVC1G126SE7-74LVC1G126SE-7,SA';body '74LVC1G126SE7';
    'A':'(2)';IN;
    'Y':'(4)';OUT;
    'VCC':'(5)';
    'GND':'(3)';
    'OE':'(1)';IN;
end_primitive;
primitive '74LVC1G17GW-74LVC1G17GW,SMLF,IA';body '74LVC1G17GW';
    'VCC':'(5)';
    'A':'(2)';IN;
    'GND':'(3)';
    'Y':'(4)';OUT;
    'NC':'(1)';OUT;
end_primitive;
primitive '74LVC1G66GV-74LVC1G66GV,SMLF,IA';body '74LVC1G66GV';
    'Y':'(1)';BIDI;
    'Z':'(2)';BIDI;
    'GND':'(3)';
    'E':'(4)';IN;
    'VCC':'(5)';
end_primitive;
primitive '74LVC1G74DP-74LVC1G74DP,SMLF,IA';body '74LVC1G74DP';
    'CP':'(1)';IN;
    'D':'(2)';IN;
    'Q_N':'(3)';OUT;
    'GND':'(4)';
    'VCC':'(8)';
    'RD_N':'(6)';IN;
    'SD_N':'(7)';IN;
    'Q':'(5)';OUT;
end_primitive;
primitive '74LVC2G07DW7-74LVC2G07DW-7,SMLA';body '74LVC2G07DW7';
    '1A':'(1)';IN;
    '2A':'(3)';IN;
    '1Y':'(6)';OUT;
    '2Y':'(4)';OUT;
    'GND':'(2)';
    'VCC':'(5)';
end_primitive;
primitive 'AP2205W57-AP2205-W5-7,SMLF,IC,A';body 'AP2205W57';
    'VOUT':'(5)';
    'ADJ||NC':'(4)';BIDI;
    'VIN':'(1)';
    'GND':'(2)';
    'EN':'(3)';IN;
end_primitive;
primitive 'AP22811AW57-AP22811AW5-7,SMLF,A';body 'AP22811AW57';
    'OUT':'(1)';OUT;
    'GND':'(2)';
    'EN':'(4)';IN;
    'FLG#':'(3)';OUT;
    'IN':'(5)';IN;
end_primitive;
primitive 'AST2600A3GP-AST2600A3-GP,SMLF,A';body 'AST2600A3GP';
    'MVREF_T5':'(T5,0,0,0,0,0)';$S;
    'MIOZ':'(P5,0,0,0,0,0)';$S;BIDI;
    'MRESET#':'(L3,0,0,0,0,0)';$S;OUT;
    'MALERT#':'(N4,0,0,0,0,0)';$S;BIDI;
    'MDQ0':'(T3,0,0,0,0,0)';$S;BIDI;
    'MDQ1':'(R4,0,0,0,0,0)';$S;BIDI;
    'MDQ2':'(U1,0,0,0,0,0)';$S;BIDI;
    'MDQ3':'(R3,0,0,0,0,0)';$S;BIDI;
    'MDQ4':'(R1,0,0,0,0,0)';$S;BIDI;
    'MDQ5':'(P1,0,0,0,0,0)';$S;BIDI;
    'MDQ6':'(P2,0,0,0,0,0)';$S;BIDI;
    'MDQ7':'(P3,0,0,0,0,0)';$S;BIDI;
    'MDQ8':'(W2,0,0,0,0,0)';$S;BIDI;
    'MDQ9':'(V3,0,0,0,0,0)';$S;BIDI;
    'MDQ10':'(W1,0,0,0,0,0)';$S;BIDI;
    'MDQ11':'(W3,0,0,0,0,0)';$S;BIDI;
    'MDQ12':'(W4,0,0,0,0,0)';$S;BIDI;
    'MDQ13':'(U4,0,0,0,0,0)';$S;BIDI;
    'MDQ14':'(V4,0,0,0,0,0)';$S;BIDI;
    'MDQ15':'(U3,0,0,0,0,0)';$S;BIDI;
    'MDQS0':'(T2,0,0,0,0,0)';$S;BIDI;
    'MDQS1':'(V2,0,0,0,0,0)';$S;BIDI;
    'MDQS0#':'(T1,0,0,0,0,0)';$S;BIDI;
    'MDQS1#':'(V1,0,0,0,0,0)';$S;BIDI;
    'GPIOW4||LCLK||ESPICK':'(AE7,0,0,0,0,0)';$S;BIDI;
    'GPIOW5||LFRAME#||ESPICS#':'(AF7,0,0,0,0,0)';$S;BIDI;
    'GPIOW6||LSIRQ#||ESPIALT#':'(AD7,0,0,0,0,0)';$S;BIDI;
    'GPIOW7||LPCRST#||ESPIRST#':'(AD8,0,0,0,0,0)';$S;BIDI;
    'GPIOF0||SD1CLK||PWM8':'(D22,0,0,0,0,0)';$S;BIDI;
    'GPIOF1||SD1CMD||PWM9':'(E22,0,0,0,0,0)';$S;BIDI;
    'GPIOF2||SD1DAT0||PWM10':'(D23,0,0,0,0,0)';$S;BIDI;
    'GPIOF3||SD1DAT1||PWM11':'(C23,0,0,0,0,0)';$S;BIDI;
    'GPIOF4||SD1DAT2||PWM12':'(C22,0,0,0,0,0)';$S;BIDI;
    'GPIOF5||SD1DAT3||PWM13':'(A25,0,0,0,0,0)';$S;BIDI;
    'GPIOF6||SD1CD#||PWM14':'(A24,0,0,0,0,0)';$S;BIDI;
    'GPIOF7||SD1WP#||PWM15':'(A23,0,0,0,0,0)';$S;BIDI;
    'GPIOG0||TXD6||SD2CLK||SALT9':'(E21,0,0,0,0,0)';$S;BIDI;
    'GPIOG1||RXD6||SD2CMD||SALT10':'(B22,0,0,0,0,0)';$S;BIDI;
    'GPIOG2||TXD7||SD2DAT0||SALT11':'(C21,0,0,0,0,0)';$S;BIDI;
    'GPIOG3||RXD7||SD2DAT1||SALT12':'(A22,0,0,0,0,0)';$S;BIDI;
    'GPIOG4||TXD8||SD2DAT2||SALT13':'(A21,0,0,0,0,0)';$S;BIDI;
    'GPIOG5||RXD8||SD2DAT3||SALT14':'(E20,0,0,0,0,0)';$S;BIDI;
    'GPIOG6||TXD9||SD2CD#||SALT15':'(D21,0,0,0,0,0)';$S;BIDI;
    'GPIOG7||RXD9||SD2WP#||SALT16':'(B21,0,0,0,0,0)';$S;BIDI;
    'PETXP':'(AE4,0,0,0,0,0)';$S;OUT;
    'PETXN':'(AE5,0,0,0,0,0)';$S;OUT;
    'PERST#':'(A7,0,0,0,0,0)';$S;IN;
    'PEREFCLKP':'(AD5,0,0,0,0,0)';$S;IN;
    'PEREFCLKN':'(AD6,0,0,0,0,0)';$S;IN;
    'PERXP':'(AF5,0,0,0,0,0)';$S;IN;
    'PERXN':'(AF6,0,0,0,0,0)';$S;IN;
    'MVREF_U5':'(U5,0,0,0,0,0)';$S;
    'MCK#':'(K1,0,0,0,0,0)';$S;OUT;
    'MBA1':'(H5,0,0,0,0,0)';$S;OUT;
    'MA3':'(H3,0,0,0,0,0)';$S;OUT;
    'MA14||MACT#':'(H1,0,0,0,0,0)';$S;OUT;
    'MBA2||MBG0':'(G3,0,0,0,0,0)';$S;OUT;
    'GPIOJ2||HVI3C4SCL||SCL2':'(E19,0,0,0,0,0)';$S;BIDI;
    'MA0':'(F3,0,0,0,0,0)';$S;OUT;
    'MA13':'(K3,0,0,0,0,0)';$S;OUT;
    'GPIOK3||SDA6':'(E13,0,0,0,0,0)';$S;BIDI;
    'MBA0':'(G4,0,0,0,0,0)';$S;OUT;
    'MA11':'(G1,0,0,0,0,0)';$S;OUT;
    'MDM0':'(N3,0,0,0,0,0)';$S;OUT;
    'GPIOJ7||HVI3C6SDA||SDA4':'(D19,0,0,0,0,0)';$S;BIDI;
    'MA6':'(M5,0,0,0,0,0)';$S;OUT;
    'MA5':'(L1,0,0,0,0,0)';$S;OUT;
    'MCS#':'(H2,0,0,0,0,0)';$S;OUT;
    'MA8':'(M1,0,0,0,0,0)';$S;OUT;
    'MA12':'(L4,0,0,0,0,0)';$S;OUT;
    'MDM1':'(R5,0,0,0,0,0)';$S;OUT;
    'GPIOK5||SDA7':'(E11,0,0,0,0,0)';$S;BIDI;
    'MA15||MBG1':'(M3,0,0,0,0,0)';$S;OUT;
    'GPIOJ0||HVI3C3SCL||SCL1':'(B20,0,0,0,0,0)';$S;BIDI;
    'GPIOK6||SCL8':'(F13,0,0,0,0,0)';$S;BIDI;
    'MA10':'(F2,0,0,0,0,0)';$S;OUT;
    'MRAS#':'(J5,0,0,0,0,0)';$S;OUT;
    'MA4':'(J3,0,0,0,0,0)';$S;OUT;
    'GPIOK4||SCL7':'(D11,0,0,0,0,0)';$S;BIDI;
    'MA9':'(N1,0,0,0,0,0)';$S;OUT;
    'GPIOJ4||HVI3C5SCL||SCL3':'(C19,0,0,0,0,0)';$S;BIDI;
    'MA1':'(K5,0,0,0,0,0)';$S;OUT;
    'GPIOK2||SCL6':'(D12,0,0,0,0,0)';$S;BIDI;
    'GPIOJ3||HVI3C4SDA||SDA2':'(D20,0,0,0,0,0)';$S;BIDI;
    'MCAS#':'(J4,0,0,0,0,0)';$S;OUT;
    'GPIOW0||LAD0||ESPID0':'(AB7,0,0,0,0,0)';$S;BIDI;
    'MCK':'(K2,0,0,0,0,0)';$S;OUT;
    'MA2':'(F1,0,0,0,0,0)';$S;OUT;
    'MWE#':'(G5,0,0,0,0,0)';$S;OUT;
    'GPIOJ6||HVI3C6SCL||SCL4':'(C20,0,0,0,0,0)';$S;BIDI;
    'MA7':'(M2,0,0,0,0,0)';$S;OUT;
    'GPIOK0||SCL5':'(A11,0,0,0,0,0)';$S;BIDI;
    'MODT':'(J1,0,0,0,0,0)';$S;OUT;
    'GPIOW3||LAD3||ESPID3':'(AC7,0,0,0,0,0)';$S;BIDI;
    'GPIOJ1||HVI3C3SDA||SDA1':'(A20,0,0,0,0,0)';$S;BIDI;
    'GPIOW2||LAD2||ESPID2':'(AC8,0,0,0,0,0)';$S;BIDI;
    'GPIOJ5||HVI3C5SDA||SDA3':'(A19,0,0,0,0,0)';$S;BIDI;
    'GPIOW1||LAD1||ESPID1':'(AB8,0,0,0,0,0)';$S;BIDI;
    'MCKE':'(L5,0,0,0,0,0)';$S;OUT;
    'GPIOK1||SDA5':'(C11,0,0,0,0,0)';$S;BIDI;
    'GPIOK7||SDA8':'(E12,0,0,0,0,0)';$S;BIDI;
    'RCREFCLKP':'(AE1,0,0,0,0,0)';$S;IN;
    'RCREFCLKN':'(AE2,0,0,0,0,0)';$S;IN;
    'RCRXP':'(AD2,0,0,0,0,0)';$S;IN;
    'RCRXN':'(AD3,0,0,0,0,0)';$S;IN;
    'RCTXP':'(AF2,0,0,0,0,0)';$S;OUT;
    'RCTXN':'(AF3,0,0,0,0,0)';$S;OUT;
    'DPTXP0':'(AC1,0,0,0,0,0)';$S;OUT;
    'DPTXN0':'(AB1,0,0,0,0,0)';$S;OUT;
    'DPAUXP':'(AC3,0,0,0,0,0)';$S;BIDI;
    'DPAUXN':'(AB3,0,0,0,0,0)';$S;BIDI;
    'DPHPD':'(C7,0,0,0,0,0)';$S;IN;
    'DPTXP1':'(AB2,0,0,0,0,0)';$S;OUT;
    'DPTXN1':'(AA2,0,0,0,0,0)';$S;OUT;
    'GPIOL0||SCL9':'(D15,0,0,0,0,0)';$S;BIDI;
    'GPIOL1||SDA9':'(A14,0,0,0,0,0)';$S;BIDI;
    'GPIOL2||SCL10':'(E15,0,0,0,0,0)';$S;BIDI;
    'GPIOL3||SDA10':'(A13,0,0,0,0,0)';$S;BIDI;
    'GPIOA0||SCL11||MDC3':'(M24,0,0,0,0,0)';$S;BIDI;
    'GPIOA1||SDA11||MDIO3':'(M25,0,0,0,0,0)';$S;BIDI;
    'GPIOA2||SCL12||MDC4':'(L26,0,0,0,0,0)';$S;BIDI;
    'GPIOA3||SDA12||MDIO4':'(K24,0,0,0,0,0)';$S;BIDI;
    'GPIOA6||MAC3LINK||SCL14||SGPM2O||SGPS2I0':'(L23,0,0,0,0,0)';$S;BIDI;
    'GPIOA7||MAC4LINK||SDA14||SGPM2I||SGPS2I1':'(K25,0,0,0,0,0)';$S;BIDI;
    'GPIOA4||MAC1LINK||SCL13||SGPM2CK||SGPS2CK':'(K26,0,0,0,0,0)';$S;BIDI;
    'GPIOA5||MAC2LINK||SDA13||SGPM2LD||SGPS2LD':'(L24,0,0,0,0,0)';$S;BIDI;
    'GPIOH0||SGPM1CK':'(A18,0,0,0,0,0)';$S;BIDI;
    'GPIOH1||SGPM1LD':'(B18,0,0,0,0,0)';$S;BIDI;
    'GPIOH2||SGPM1O':'(C18,0,0,0,0,0)';$S;BIDI;
    'GPIOH3||SGPM1I':'(A17,0,0,0,0,0)';$S;BIDI;
    'GPIOH4||SGPS1CK||SCL15':'(D18,0,0,0,0,0)';$S;BIDI;
    'GPIOH5||SGPS1LD||SDA15':'(B17,0,0,0,0,0)';$S;BIDI;
    'GPIOH6||SGPS1I0||SCL16':'(C17,0,0,0,0,0)';$S;BIDI;
    'GPIOH7||SGPS1I1||SDA16':'(E18,0,0,0,0,0)';$S;BIDI;
    'GPIOS2||PEWAKE#':'(T26,0,0,0,0,0)';$S;BIDI;
    'GPIOS3||OSCCLK':'(R24,0,0,0,0,0)';$S;BIDI;
    'FWSPICS0#':'(0,AB14,0,0,0,0)';$S;OUT;
    'GPIOM0||NCTS1':'(0,D14,0,0,0,0)';$S;BIDI;
    'GPIOM1||NDCD1':'(0,B13,0,0,0,0)';$S;BIDI;
    'GPIOM2||NDSR1':'(0,A12,0,0,0,0)';$S;BIDI;
    'GPIOM3||NRI1':'(0,E14,0,0,0,0)';$S;BIDI;
    'GPIOM4||NDTR1':'(0,B12,0,0,0,0)';$S;BIDI;
    'GPIOM5||NRTS1':'(0,C12,0,0,0,0)';$S;BIDI;
    'GPIOM6||TXD1':'(0,C13,0,0,0,0)';$S;BIDI;
    'GPIOM7||RXD1':'(0,D13,0,0,0,0)';$S;BIDI;
    'GPION0||NCTS2':'(0,P25,0,0,0,0)';$S;BIDI;
    'GPION1||NDCD2':'(0,N23,0,0,0,0)';$S;BIDI;
    'GPION2||NDSR2':'(0,N25,0,0,0,0)';$S;BIDI;
    'GPION3||NRI2':'(0,N24,0,0,0,0)';$S;BIDI;
    'GPION4||NDTR2':'(0,P26,0,0,0,0)';$S;BIDI;
    'GPION5||NRTS2':'(0,M23,0,0,0,0)';$S;BIDI;
    'GPION6||TXD2':'(0,N26,0,0,0,0)';$S;BIDI;
    'GPION7||RXD2':'(0,M26,0,0,0,0)';$S;BIDI;
    'GPIOL5||RXD3':'(0,F15,0,0,0,0)';$S;BIDI;
    'GPIOL4||TXD3':'(0,C15,0,0,0,0)';$S;BIDI;
    'FWSPICS1#':'(0,AA13,0,0,0,0)';$S;OUT;
    'FWSPICS2#':'(0,AC13,0,0,0,0)';$S;OUT;
    'GPIOV0||SIOS3#':'(0,AB15,0,0,0,0)';$S;BIDI;
    'GPIOV1||SIOS5#':'(0,AF14,0,0,0,0)';$S;BIDI;
    'GPIOV2||SIOPWREQ#':'(0,AD14,0,0,0,0)';$S;BIDI;
    'GPIOV3||SIOONCTRL#':'(0,AC15,0,0,0,0)';$S;BIDI;
    'GPIOV4||SIOPWRGD':'(0,AE15,0,0,0,0)';$S;BIDI;
    'GPIOV5||LPCPD#':'(0,AE14,0,0,0,0)';$S;BIDI;
    'GPIOV6||LPCPME#':'(0,AD15,0,0,0,0)';$S;BIDI;
    'GPIOV7||LPCSMI#':'(0,AF15,0,0,0,0)';$S;BIDI;
    'FWSPICK':'(0,AF13,0,0,0,0)';$S;OUT;
    'FWSPIMOSI':'(0,AC14,0,0,0,0)';$S;BIDI;
    'FWSPIMISO':'(0,AB13,0,0,0,0)';$S;BIDI;
    'GPIOY5||FWSPIDQ3':'(0,AF12,0,0,0,0)';$S;BIDI;
    'GPIOY4||FWSPIDQ2':'(0,AE12,0,0,0,0)';$S;BIDI;
    'GPIOY6||FWSPIABR':'(0,AC12,0,0,0,0)';$S;BIDI;
    'GPIOY7||FWSPIWP#':'(0,AB12,0,0,0,0)';$S;BIDI;
    'GPIOZ3||SPI1CK':'(0,AB11,0,0,0,0)';$S;BIDI;
    'GPIOZ4||SPI1MOSI':'(0,AC11,0,0,0,0)';$S;BIDI;
    'GPIOZ5||SPI1MISO':'(0,AA11,0,0,0,0)';$S;BIDI;
    'GPIOZ6||SPI1DQ2||TXD13':'(0,AD11,0,0,0,0)';$S;BIDI;
    'GPIOZ7||SPI1DQ3||RXD13':'(0,AF10,0,0,0,0)';$S;BIDI;
    'SPI1CS0#':'(0,AD13,0,0,0,0)';$S;OUT;
    'GPIOZ0||SPI1CS1#':'(0,AC10,0,0,0,0)';$S;BIDI;
    'GPIOZ1||SPI1ABR':'(0,AD10,0,0,0,0)';$S;BIDI;
    'GPIOZ2||SPI1WP#':'(0,AE10,0,0,0,0)';$S;BIDI;
    'GPIOX3||SPI2CK':'(0,AF8,0,0,0,0)';$S;BIDI;
    'GPIOX4||SPI2MOSI':'(0,AB9,0,0,0,0)';$S;BIDI;
    'GPIOX5||SPI2MISO':'(0,AD9,0,0,0,0)';$S;BIDI;
    'GPIOX6||SPI2DQ2||TXD12':'(0,AF9,0,0,0,0)';$S;BIDI;
    'GPIOX7||SPI2DQ3||RXD12':'(0,AB10,0,0,0,0)';$S;BIDI;
    'GPIOX0||SPI2CS0#':'(0,AE8,0,0,0,0)';$S;BIDI;
    'GPIOX1||SPI2CS1#':'(0,AA9,0,0,0,0)';$S;BIDI;
    'GPIOX2||SPI2CS2#':'(0,AC9,0,0,0,0)';$S;BIDI;
    'GPIOB0||SALT1':'(0,J26,0,0,0,0)';$S;BIDI;
    'GPIOB1||SALT2':'(0,K23,0,0,0,0)';$S;BIDI;
    'GPIOB2||SALT3':'(0,H26,0,0,0,0)';$S;BIDI;
    'GPIOB3||SALT4':'(0,J25,0,0,0,0)';$S;BIDI;
    'GPIOB4||MDC2':'(0,J23,0,0,0,0)';$S;BIDI;
    'GPIOB5||MDIO2':'(0,G26,0,0,0,0)';$S;BIDI;
    'GPIOB6||TXD4':'(0,H25,0,0,0,0)';$S;BIDI;
    'GPIOB7||RXD4':'(0,J24,0,0,0,0)';$S;BIDI;
    'GPIOY0||SALT5||WDTRST1#':'(0,AF11,0,0,0,0)';$S;BIDI;
    'GPIOY1||SALT6||WDTRST2#':'(0,AD12,0,0,0,0)';$S;BIDI;
    'GPIOY2||SALT7||WDTRST3#':'(0,AE11,0,0,0,0)';$S;BIDI;
    'GPIOY3||SALT8||WDTRST4#':'(0,AA12,0,0,0,0)';$S;BIDI;
    'TXD5':'(0,C8,0,0,0,0)';$S;OUT;
    'RXD5':'(0,D8,0,0,0,0)';$S;IN;
    'RGMII3RXCK||RMII3RCLKI||GPIOC6':'(0,G23,0,0,0,0)';$S;BIDI;
    'RGMII3RXCTL||GPIOC7':'(0,G24,0,0,0,0)';$S;BIDI;
    'RGMII3RXD0||RMII3RXD0||GPIOD0':'(0,F23,0,0,0,0)';$S;BIDI;
    'RGMII3RXD1||RMII3RXD1||GPIOD1':'(0,F26,0,0,0,0)';$S;BIDI;
    'RGMII3RXD2||RMII3CRSDV||GPIOD2':'(0,F25,0,0,0,0)';$S;BIDI;
    'RGMII3RXD3||RMII3RXER||GPIOD3':'(0,E26,0,0,0,0)';$S;BIDI;
    'RGMII4RXCK||RMII4RCLKI||NCTS4||GPIOE2':'(0,C25,0,0,0,0)';$S;BIDI;
    'RGMII4RXCTL||NDCD4||GPIOE3':'(0,C26,0,0,0,0)';$S;BIDI;
    'RGMII4RXD0||RMII4RXD0||NDSR4||GPIOE4':'(0,C24,0,0,0,0)';$S;BIDI;
    'RGMII4RXD1||RMII4RXD1||NRI4||GPIOE5':'(0,B26,0,0,0,0)';$S;BIDI;
    'RGMII4RXD2||RMII4CRSDV||NDTR4||GPIOE6':'(0,B25,0,0,0,0)';$S;BIDI;
    'RGMII4RXD3||RMII4RXER||NRTS4||GPIOE7':'(0,B24,0,0,0,0)';$S;BIDI;
    'RGMII4TXCK||RMII4RCLKO||NCTS3||GPIOD4':'(0,F24,0,0,0,0)';$S;BIDI;
    'RGMII4TXCTL||RMII4TXEN||NDCD3||GPIOD5':'(0,E23,0,0,0,0)';$S;BIDI;
    'RGMII4TXD0||RMII4TXD0||NDSR3||GPIOD6':'(0,E24,0,0,0,0)';$S;BIDI;
    'RGMII4TXD1||RMII4TXD1||NRI3||GPIOD7':'(0,E25,0,0,0,0)';$S;BIDI;
    'RGMII4TXD2||NDTR3||GPIOE0':'(0,D26,0,0,0,0)';$S;BIDI;
    'RGMII4TXD3||NRTS3||GPIOE1':'(0,D24,0,0,0,0)';$S;BIDI;
    'RGMII3TXCK||RMII3RCLKO||GPIOC0':'(0,H24,0,0,0,0)';$S;BIDI;
    'RGMII3TXCTL||RMII3TXEN||GPIOC1':'(0,J22,0,0,0,0)';$S;BIDI;
    'RGMII3TXD0||RMII3TXD0||GPIOC2':'(0,H22,0,0,0,0)';$S;BIDI;
    'RGMII3TXD1||RMII3TXD1||GPIOC3':'(0,H23,0,0,0,0)';$S;BIDI;
    'RGMII3TXD2||GPIOC4':'(0,G22,0,0,0,0)';$S;BIDI;
    'RGMII3TXD3||GPIOC5':'(0,F22,0,0,0,0)';$S;BIDI;
    'RGMIICK':'(0,A10,0,0,0,0)';$S;IN;
    'GPIOS0||MDC1':'(0,R23,0,0,0,0)';$S;BIDI;
    'GPIOS1||MDIO1':'(0,T25,0,0,0,0)';$S;BIDI;
    'GPIOS5||RXD10':'(0,P24,0,0,0,0)';$S;BIDI;
    'GPIOS6||TXD11':'(0,P23,0,0,0,0)';$S;BIDI;
    'GPIOS7||RXD11':'(0,T24,0,0,0,0)';$S;BIDI;
    'GPIOS4||TXD10':'(0,R26,0,0,0,0)';$S;BIDI;
    'GPIOI6||SIOPBI#':'(0,B16,0,0,0,0)';$S;BIDI;
    'GPIOI5||SIOPBO#':'(0,E16,0,0,0,0)';$S;BIDI;
    'GPIOI7||SIOSCI#':'(0,A15,0,0,0,0)';$S;BIDI;
    'RGMII1RXCK||RMII1RCLKI||GPIO18A6':'(0,0,B3,0,0,0)';$S;BIDI;
    'RGMII1RXCTL||GPIO18A7':'(0,0,A2,0,0,0)';$S;BIDI;
    'RGMII1RXD0||RMII1RXD0||GPIO18B0':'(0,0,B2,0,0,0)';$S;BIDI;
    'RGMII1RXD1||RMII1RXD1||GPIO18B1':'(0,0,B1,0,0,0)';$S;BIDI;
    'RGMII1RXD2||RMII1CRSDV||GPIO18B2':'(0,0,C4,0,0,0)';$S;BIDI;
    'RGMII1RXD3||RMII1RXER||GPIO18B3':'(0,0,E5,0,0,0)';$S;BIDI;
    'RGMII1TXCK||RMII1RCLKO||GPIO18A0':'(0,0,C6,0,0,0)';$S;BIDI;
    'RGMII1TXCTL||RMII1TXEN||GPIO18A1':'(0,0,D6,0,0,0)';$S;BIDI;
    'RGMII1TXD0||RMII1TXD0||GPIO18A2':'(0,0,D5,0,0,0)';$S;BIDI;
    'RGMII1TXD1||RMII1TXD1||GPIO18A3':'(0,0,A3,0,0,0)';$S;BIDI;
    'RGMII1TXD2||GPIO18A4':'(0,0,C5,0,0,0)';$S;BIDI;
    'RGMII1TXD3||GPIO18A5':'(0,0,E6,0,0,0)';$S;BIDI;
    'RGMII2RXCK||RMII2RCLKI||GPIO18C2':'(0,0,D2,0,0,0)';$S;BIDI;
    'RGMII2RXCTL||GPIO18C3':'(0,0,E3,0,0,0)';$S;BIDI;
    'RGMII2RXD0||RMII2RXD0||GPIO18C4':'(0,0,D1,0,0,0)';$S;BIDI;
    'RGMII2RXD1||RMII2RXD1||GPIO18C5':'(0,0,F4,0,0,0)';$S;BIDI;
    'RGMII2RXD2||RMII2CRSDV||GPIO18C6':'(0,0,E2,0,0,0)';$S;BIDI;
    'RGMII2RXD3||RMII2RXER||GPIO18C7':'(0,0,E1,0,0,0)';$S;BIDI;
    'RGMII2TXCK||RMII2RCLKO||GPIO18B4':'(0,0,D4,0,0,0)';$S;BIDI;
    'RGMII2TXCTL||RMII2TXEN||GPIO18B5':'(0,0,C2,0,0,0)';$S;BIDI;
    'RGMII2TXD0||RMII2TXD0||GPIO18B6':'(0,0,C1,0,0,0)';$S;BIDI;
    'RGMII2TXD1||RMII2TXD1||GPIO18B7':'(0,0,D3,0,0,0)';$S;BIDI;
    'RGMII2TXD2||GPIO18C0':'(0,0,E4,0,0,0)';$S;BIDI;
    'RGMII2TXD3||GPIO18C1':'(0,0,F5,0,0,0)';$S;BIDI;
    'GPIO18D0||EMMCCLK':'(0,0,AB4,0,0,0)';$S;BIDI;
    'GPIO18D1||EMMCCMD':'(0,0,AA4,0,0,0)';$S;BIDI;
    'GPIO18D2||EMMCDAT0':'(0,0,AC4,0,0,0)';$S;BIDI;
    'GPIO18D3||EMMCDAT1':'(0,0,AA5,0,0,0)';$S;BIDI;
    'GPIO18D4||EMMCDAT2':'(0,0,Y5,0,0,0)';$S;BIDI;
    'GPIO18D5||EMMCDAT3':'(0,0,AB5,0,0,0)';$S;BIDI;
    'GPIO18D6||EMMCCD#':'(0,0,AC5,0,0,0)';$S;BIDI;
    'GPIO18D7||EMMCWP#':'(0,0,AB6,0,0,0)';$S;BIDI;
    'GPIO18E0||EMMCDAT4||FWSPI18CS#||VBCS#':'(0,0,Y1,0,0,0)';$S;BIDI;
    'GPIO18E1||EMMCDAT5||FWSPI18CK||VBCK':'(0,0,Y2,0,0,0)';$S;BIDI;
    'GPIO18E2||EMMCDAT6||FWSPI18MOSI||VBMOSI':'(0,0,Y3,0,0,0)';$S;BIDI;
    'GPIO18E3||EMMCDAT7||FWSPI18MISO||VBMISO':'(0,0,Y4,0,0,0)';$S;BIDI;
    'I3C1SCL':'(0,0,AF23,0,0,0)';$S;BIDI;
    'I3C1SDA':'(0,0,AE24,0,0,0)';$S;BIDI;
    'I3C2SCL':'(0,0,AF22,0,0,0)';$S;BIDI;
    'I3C2SDA':'(0,0,AE22,0,0,0)';$S;BIDI;
    'I3C3SCL||FSI1CLK':'(0,0,AF25,0,0,0)';$S;BIDI;
    'I3C3SDA||FSI1DATA':'(0,0,AE26,0,0,0)';$S;BIDI;
    'I3C4SCL||FSI2CLK':'(0,0,AE25,0,0,0)';$S;BIDI;
    'I3C4SDA||FSI2DATA':'(0,0,AF24,0,0,0)';$S;BIDI;
    'DACB':'(0,0,0,AD21,0,0)';$S;OUT;
    'DACG':'(0,0,0,AE21,0,0)';$S;OUT;
    'DACR':'(0,0,0,AF21,0,0)';$S;OUT;
    'USB2AV33':'(0,0,0,J10,0,0)';$S;
    'USB2A_DN':'(0,0,0,B4,0,0)';$S;BIDI;
    'USB2A_DP':'(0,0,0,A4,0,0)';$S;BIDI;
    'USB2B_DN':'(0,0,0,B6,0,0)';$S;BIDI;
    'USB2B_DP':'(0,0,0,A6,0,0)';$S;BIDI;
    'ADC0||GPIT0':'(0,0,0,AD20,0,0)';$S;IN;
    'ADC1||GPIT1':'(0,0,0,AC18,0,0)';$S;IN;
    'ADC2||GPIT2':'(0,0,0,AE19,0,0)';$S;IN;
    'ADC3||GPIT3':'(0,0,0,AD19,0,0)';$S;IN;
    'ADC4||GPIT4':'(0,0,0,AC19,0,0)';$S;IN;
    'ADC5||GPIT5':'(0,0,0,AB19,0,0)';$S;IN;
    'ADC6||GPIT6':'(0,0,0,AB18,0,0)';$S;IN;
    'ADC7||GPIT7':'(0,0,0,AE18,0,0)';$S;IN;
    'ADC8||GPIU0||SALT9':'(0,0,0,AB16,0,0)';$S;IN;
    'ADC9||GPIU1||SALT10':'(0,0,0,AA17,0,0)';$S;IN;
    'ADC10||GPIU2||SALT11':'(0,0,0,AB17,0,0)';$S;IN;
    'ADC11||GPIU3||SALT12':'(0,0,0,AE16,0,0)';$S;IN;
    'ADC12||GPIU4||SALT13':'(0,0,0,AC16,0,0)';$S;IN;
    'ADC13||GPIU5||SALT14':'(0,0,0,AA16,0,0)';$S;IN;
    'ADC14||GPIU6||SALT15':'(0,0,0,AD16,0,0)';$S;IN;
    'ADC15||GPIU7||SALT16':'(0,0,0,AC17,0,0)';$S;IN;
    'ENTEST':'(0,0,0,C10,0,0)';$S;IN;
    'SRST#':'(0,0,0,E10,0,0)';$S;IN;
    'EXTRST#':'(0,0,0,B10,0,0)';$S;IN;
    'CLKIN':'(0,0,0,D10,0,0)';$S;IN;
    'RSTIND#':'(0,0,0,B7,0,0)';$S;OUT;
    'NTRST||MNTRST1':'(0,0,0,F11,0,0)';$S;BIDI;
    'TCK||MTCK1':'(0,0,0,B9,0,0)';$S;BIDI;
    'TDI||MTDI1':'(0,0,0,D9,0,0)';$S;BIDI;
    'TDO||MTDO1':'(0,0,0,C9,0,0)';$S;BIDI;
    'TMS||MTMS1':'(0,0,0,A9,0,0)';$S;BIDI;
    'GPIOL6||VGAHS':'(0,0,0,B14,0,0)';$S;BIDI;
    'GPIOL7||VGAVS':'(0,0,0,C14,0,0)';$S;BIDI;
    'DDCCLK':'(0,0,0,B8,0,0)';$S;OUT;
    'DDCDAT':'(0,0,0,A8,0,0)';$S;OUT;
    'GPIOO0||PWM0':'(0,0,0,AD26,0,0)';$S;BIDI;
    'GPIOO1||PWM1':'(0,0,0,AD22,0,0)';$S;BIDI;
    'GPIOO2||PWM2':'(0,0,0,AD23,0,0)';$S;BIDI;
    'GPIOO3||PWM3':'(0,0,0,AD24,0,0)';$S;BIDI;
    'GPIOO4||PWM4':'(0,0,0,AD25,0,0)';$S;BIDI;
    'GPIOO5||PWM5':'(0,0,0,AC22,0,0)';$S;BIDI;
    'GPIOO6||PWM6':'(0,0,0,AC24,0,0)';$S;BIDI;
    'GPIOO7||PWM7':'(0,0,0,AC23,0,0)';$S;BIDI;
    'GPIOQ0||TACH0':'(0,0,0,AA25,0,0)';$S;BIDI;
    'GPIOQ1||TACH1':'(0,0,0,AB25,0,0)';$S;BIDI;
    'GPIOQ2||TACH2':'(0,0,0,Y24,0,0)';$S;BIDI;
    'GPIOQ3||TACH3':'(0,0,0,AB26,0,0)';$S;BIDI;
    'GPIOQ4||TACH4':'(0,0,0,Y26,0,0)';$S;BIDI;
    'GPIOQ5||TACH5':'(0,0,0,AC26,0,0)';$S;BIDI;
    'GPIOQ6||TACH6':'(0,0,0,Y25,0,0)';$S;BIDI;
    'GPIOQ7||TACH7':'(0,0,0,AA26,0,0)';$S;BIDI;
    'GPIOR0||TACH8':'(0,0,0,V25,0,0)';$S;BIDI;
    'GPIOR1||TACH9':'(0,0,0,U24,0,0)';$S;BIDI;
    'GPIOR2||TACH10':'(0,0,0,V24,0,0)';$S;BIDI;
    'GPIOR3||TACH11':'(0,0,0,V26,0,0)';$S;BIDI;
    'GPIOR4||TACH12':'(0,0,0,U25,0,0)';$S;BIDI;
    'GPIOR5||TACH13':'(0,0,0,T23,0,0)';$S;BIDI;
    'GPIOR6||TACH14':'(0,0,0,W26,0,0)';$S;BIDI;
    'GPIOR7||TACH15':'(0,0,0,U26,0,0)';$S;BIDI;
    'GPIOP0||PWM8||THRUIN0':'(0,0,0,AB22,0,0)';$S;BIDI;
    'GPIOP1||PWM9||THRUOUT0':'(0,0,0,W24,0,0)';$S;BIDI;
    'GPIOP2||PWM10||THRUIN1':'(0,0,0,AA23,0,0)';$S;BIDI;
    'GPIOP3||PWM11||THRUOUT1':'(0,0,0,AA24,0,0)';$S;BIDI;
    'GPIOP4||PWM12||THRUIN2':'(0,0,0,W23,0,0)';$S;BIDI;
    'GPIOP5||PWM13||THRUOUT2':'(0,0,0,AB23,0,0)';$S;BIDI;
    'GPIOP6||PWM14':'(0,0,0,AB24,0,0)';$S;BIDI;
    'GPIOP7||PWM15||HBLED#':'(0,0,0,Y23,0,0)';$S;BIDI;
    'SSPRST#':'(0,0,0,D7,0,0)';$S;IN;
    'USB2AV18':'(0,0,0,K10,0,0)';$S;
    'PECIVDD':'(0,0,0,AA18,0,0)';$S;
    'PECI':'(0,0,0,AF16,0,0)';$S;BIDI;
    'GPIOI4||MTDO2':'(0,0,0,C16,0,0)';$S;BIDI;
    'GPIOI3||MTMS2||RXD13':'(0,0,0,D16,0,0)';$S;BIDI;
    'GPIOI2||MTCK2||TXD13':'(0,0,0,E17,0,0)';$S;BIDI;
    'GPIOI0||MNTRST2||TXD12':'(0,0,0,D17,0,0)';$S;BIDI;
    'GPIOI1||MTDI2||RXD12':'(0,0,0,A16,0,0)';$S;BIDI;
    'CHASI#':'(0,0,0,AB21,0,0)';$S;IN;
    'ADCREXT0':'(0,0,0,0,AF20,0)';$S;OUT;
    'ADCVREFN0':'(0,0,0,0,AB20,0)';$S;OUT;
    'ADCVREFP0':'(0,0,0,0,AC20,0)';$S;OUT;
    'ADCAV33_Y21':'(0,0,0,0,Y21,0)';$S;
    'DACAV33_V21':'(0,0,0,0,V21,0)';$S;
    'DACRSET':'(0,0,0,0,AC21,0)';$S;BIDI;
    'PLLAVDD_E7':'(0,0,0,0,E7,0)';$S;
    'PLLAHVDD':'(0,0,0,0,H14,0)';$S;
    'ADCVREFP1':'(0,0,0,0,AD17,0)';$S;OUT;
    'ADCVREFN1':'(0,0,0,0,AD18,0)';$S;OUT;
    'ADCREXT1':'(0,0,0,0,AF18,0)';$S;OUT;
    'IV10D_L9':'(0,0,0,0,L9,0)';$S;
    'IV10D_L10':'(0,0,0,0,L10,0)';$S;
    'IV10D_M8':'(0,0,0,0,M8,0)';$S;
    'AVDDPLL':'(0,0,0,0,N5,0)';$S;
    'MVDD_G6':'(0,0,0,0,G6,0)';$S;
    'PLLAVDD_F7':'(0,0,0,0,F7,0)';$S;
    'DACAV33_W21':'(0,0,0,0,W21,0)';$S;
    'PLLDVDD_E9':'(0,0,0,0,E9,0)';$S;
    'PLLDVDD_F9':'(0,0,0,0,F9,0)';$S;
    'RC_VCC10A':'(0,0,0,0,T9,0)';$S;
    'RC_VCC18A':'(0,0,0,0,V9,0)';$S;
    'PE_VCC10A':'(0,0,0,0,T10,0)';$S;
    'PE_VCC18A':'(0,0,0,0,V10,0)';$S;
    'DP_VCC18A':'(0,0,0,0,V8,0)';$S;
    'DP_VCC10A':'(0,0,0,0,T8,0)';$S;
    'MVDD_H6':'(0,0,0,0,H6,0)';$S;
    'MVDD_J6':'(0,0,0,0,J6,0)';$S;
    'MVDD_K6':'(0,0,0,0,K6,0)';$S;
    'MVDD_L6':'(0,0,0,0,L6,0)';$S;
    'MVDD_P6':'(0,0,0,0,P6,0)';$S;
    'MVDD_R6':'(0,0,0,0,R6,0)';$S;
    'MVDD_T6':'(0,0,0,0,T6,0)';$S;
    'MVDD_CK':'(0,0,0,0,M6,0)';$S;
    'IV12D_K16':'(0,0,0,0,K16,0)';$S;
    'IV12D_K17':'(0,0,0,0,K17,0)';$S;
    'IV12D_K18':'(0,0,0,0,K18,0)';$S;
    'IV12D_K19':'(0,0,0,0,K19,0)';$S;
    'IV12D_L14':'(0,0,0,0,L14,0)';$S;
    'IV12D_M14':'(0,0,0,0,M14,0)';$S;
    'IV12D_N14':'(0,0,0,0,N14,0)';$S;
    'IV12D_P14':'(0,0,0,0,P14,0)';$S;
    'IV12D_R14':'(0,0,0,0,R14,0)';$S;
    'IV12D_T14':'(0,0,0,0,T14,0)';$S;
    'IV12D_L21':'(0,0,0,0,L21,0)';$S;
    'IV12D_M21':'(0,0,0,0,M21,0)';$S;
    'IV12D_N21':'(0,0,0,0,N21,0)';$S;
    'IV12D_P21':'(0,0,0,0,P21,0)';$S;
    'IV12D_R21':'(0,0,0,0,R21,0)';$S;
    'IV12D_T21':'(0,0,0,0,T21,0)';$S;
    'IV12D_U15':'(0,0,0,0,U15,0)';$S;
    'IV12D_U16':'(0,0,0,0,U16,0)';$S;
    'IV12D_U17':'(0,0,0,0,U17,0)';$S;
    'IV12D_U18':'(0,0,0,0,U18,0)';$S;
    'RVDD_L22':'(0,0,0,0,L22,0)';$S;
    'RVDD_M22':'(0,0,0,0,M22,0)';$S;
    'RVDD_J21':'(0,0,0,0,J21,0)';$S;
    'RVDD_K21':'(0,0,0,0,K21,0)';$S;
    'SD1VDD_G21':'(0,0,0,0,G21,0)';$S;
    'SD2VDD_H18':'(0,0,0,0,H18,0)';$S;
    'LPVDD':'(0,0,0,0,W15,0)';$S;
    'I3CVDDH_F19':'(0,0,0,0,F19,0)';$S;
    'IV10D_N8':'(0,0,0,0,N8,0)';$S;
    'IV10D_P8':'(0,0,0,0,P8,0)';$S;
    'IV10D_M11':'(0,0,0,0,M11,0)';$S;
    'IV10D_N11':'(0,0,0,0,N11,0)';$S;
    'IV10D_P11':'(0,0,0,0,P11,0)';$S;
    'IV10D_R9':'(0,0,0,0,R9,0)';$S;
    'PV18D_U6':'(0,0,0,0,U6,0)';$S;
    'PV18D_V6':'(0,0,0,0,V6,0)';$S;
    'PV18D_H8':'(0,0,0,0,H8,0)';$S;
    'PV18D_J8':'(0,0,0,0,J8,0)';$S;
    'PV18D_RGM_H12':'(0,0,0,0,H12,0)';$S;
    'PV33D_H16':'(0,0,0,0,H16,0)';$S;
    'PV33D_H17':'(0,0,0,0,H17,0)';$S;
    'PV33D_W16':'(0,0,0,0,W16,0)';$S;
    'PV33D_W17':'(0,0,0,0,W17,0)';$S;
    'PV33D_W18':'(0,0,0,0,W18,0)';$S;
    'PV33D_W19':'(0,0,0,0,W19,0)';$S;
    'PV33D_N22':'(0,0,0,0,N22,0)';$S;
    'PV33D_P22':'(0,0,0,0,P22,0)';$S;
    'PV33D_R22':'(0,0,0,0,R22,0)';$S;
    'PV33D_T22':'(0,0,0,0,T22,0)';$S;
    'BATVDD':'(0,0,0,0,V23,0)';$S;
    'PV18D_SLI_L13':'(0,0,0,0,L13,0)';$S;
    'PV18D_SLI_M13':'(0,0,0,0,M13,0)';$S;
    'PV18D_SLI_N13':'(0,0,0,0,N13,0)';$S;
    'PV18D_SLI_P13':'(0,0,0,0,P13,0)';$S;
    'PV18D_SLI_R13':'(0,0,0,0,R13,0)';$S;
    'PV18D_SLI_T13':'(0,0,0,0,T13,0)';$S;
    'PV18D_SLI_U13':'(0,0,0,0,U13,0)';$S;
    'PV18D_SLI_V13':'(0,0,0,0,V13,0)';$S;
    'PV18D_SLI_W13':'(0,0,0,0,W13,0)';$S;
    'PV18D_SLI_W14':'(0,0,0,0,W14,0)';$S;
    'ADCAV33_AA21':'(0,0,0,0,AA21,0)';$S;
    'PV18D_RGM_J12':'(0,0,0,0,J12,0)';$S;
    'IV10D_R10':'(0,0,0,0,R10,0)';$S;
    'ADCVREFEXT0':'(0,0,0,0,AF19,0)';$S;
    'ADCVREFEXT1':'(0,0,0,0,AF17,0)';$S;
    'PV18D_N12':'(0,0,0,0,N12,0)';$S;
    'PV18D_P12':'(0,0,0,0,P12,0)';$S;
    'PV18D_R12':'(0,0,0,0,R12,0)';$S;
    'SD1VDD_H21':'(0,0,0,0,H21,0)';$S;
    'SD2VDD_H19':'(0,0,0,0,H19,0)';$S;
    'I3CVDDH_F20':'(0,0,0,0,F20,0)';$S;
    'PV33D_H15':'(0,0,0,0,H15,0)';$S;
    'DPLLAVDD':'(0,0,0,0,J9,0)';$S;
    'I3CVDDL1':'(0,0,0,0,V22,0)';$S;
    'I3CVDDL2':'(0,0,0,0,U21,0)';$S;
    'PV33D_RGM_K11':'(0,0,0,0,K11,0)';$S;
    'PV33D_RGM_K12':'(0,0,0,0,K12,0)';$S;
    'GND_A1':'(0,0,0,0,0,A1)';$S;
    'GND_A5':'(0,0,0,0,0,A5)';$S;
    'GND_A26':'(0,0,0,0,0,A26)';$S;
    'GND_B5':'(0,0,0,0,0,B5)';$S;
    'GND_B11':'(0,0,0,0,0,B11)';$S;
    'GND_B15':'(0,0,0,0,0,B15)';$S;
    'GND_B19':'(0,0,0,0,0,B19)';$S;
    'GND_B23':'(0,0,0,0,0,B23)';$S;
    'GND_C3':'(0,0,0,0,0,C3)';$S;
    'GND_D25':'(0,0,0,0,0,D25)';$S;
    'GND_E8':'(0,0,0,0,0,E8)';$S;
    'GND_F6':'(0,0,0,0,0,F6)';$S;
    'GND_F8':'(0,0,0,0,0,F8)';$S;
    'GND_F10':'(0,0,0,0,0,F10)';$S;
    'GND_F12':'(0,0,0,0,0,F12)';$S;
    'GND_F14':'(0,0,0,0,0,F14)';$S;
    'GND_F16':'(0,0,0,0,0,F16)';$S;
    'GND_F17':'(0,0,0,0,0,F17)';$S;
    'GND_F18':'(0,0,0,0,0,F18)';$S;
    'GND_F21':'(0,0,0,0,0,F21)';$S;
    'GND_G2':'(0,0,0,0,0,G2)';$S;
    'GND_G25':'(0,0,0,0,0,G25)';$S;
    'GND_H4':'(0,0,0,0,0,H4)';$S;
    'GND_H9':'(0,0,0,0,0,H9)';$S;
    'GND_H10':'(0,0,0,0,0,H10)';$S;
    'GND_H11':'(0,0,0,0,0,H11)';$S;
    'GND_H13':'(0,0,0,0,0,H13)';$S;
    'GND_J2':'(0,0,0,0,0,J2)';$S;
    'GND_J11':'(0,0,0,0,0,J11)';$S;
    'GND_J13':'(0,0,0,0,0,J13)';$S;
    'GND_J14':'(0,0,0,0,0,J14)';$S;
    'GND_J15':'(0,0,0,0,0,J15)';$S;
    'GND_J16':'(0,0,0,0,0,J16)';$S;
    'GND_J17':'(0,0,0,0,0,J17)';$S;
    'GND_J18':'(0,0,0,0,0,J18)';$S;
    'GND_J19':'(0,0,0,0,0,J19)';$S;
    'GND_K4':'(0,0,0,0,0,K4)';$S;
    'GND_K8':'(0,0,0,0,0,K8)';$S;
    'GND_K9':'(0,0,0,0,0,K9)';$S;
    'GND_K13':'(0,0,0,0,0,K13)';$S;
    'GND_K14':'(0,0,0,0,0,K14)';$S;
    'GND_K15':'(0,0,0,0,0,K15)';$S;
    'GND_K22':'(0,0,0,0,0,K22)';$S;
    'GND_L2':'(0,0,0,0,0,L2)';$S;
    'GND_L8':'(0,0,0,0,0,L8)';$S;
    'GND_L11':'(0,0,0,0,0,L11)';$S;
    'GND_L12':'(0,0,0,0,0,L12)';$S;
    'GND_L15':'(0,0,0,0,0,L15)';$S;
    'GND_L16':'(0,0,0,0,0,L16)';$S;
    'GND_L17':'(0,0,0,0,0,L17)';$S;
    'GND_R2':'(0,0,0,0,0,R2)';$S;
    'GND_R8':'(0,0,0,0,0,R8)';$S;
    'GND_R11':'(0,0,0,0,0,R11)';$S;
    'GND_R15':'(0,0,0,0,0,R15)';$S;
    'GND_R16':'(0,0,0,0,0,R16)';$S;
    'GND_R17':'(0,0,0,0,0,R17)';$S;
    'GND_R18':'(0,0,0,0,0,R18)';$S;
    'GND_R19':'(0,0,0,0,0,R19)';$S;
    'GND_R25':'(0,0,0,0,0,R25)';$S;
    'GND_T4':'(0,0,0,0,0,T4)';$S;
    'GND_T11':'(0,0,0,0,0,T11)';$S;
    'GND_T12':'(0,0,0,0,0,T12)';$S;
    'GND_T15':'(0,0,0,0,0,T15)';$S;
    'GND_T16':'(0,0,0,0,0,T16)';$S;
    'GND_T17':'(0,0,0,0,0,T17)';$S;
    'GND_T18':'(0,0,0,0,0,T18)';$S;
    'GND_T19':'(0,0,0,0,0,T19)';$S;
    'GND_U2':'(0,0,0,0,0,U2)';$S;
    'GND_U8':'(0,0,0,0,0,U8)';$S;
    'GND_U9':'(0,0,0,0,0,U9)';$S;
    'GND_U10':'(0,0,0,0,0,U10)';$S;
    'GND_U11':'(0,0,0,0,0,U11)';$S;
    'GND_U12':'(0,0,0,0,0,U12)';$S;
    'GND_U14':'(0,0,0,0,0,U14)';$S;
    'GND_U19':'(0,0,0,0,0,U19)';$S;
    'GND_U22':'(0,0,0,0,0,U22)';$S;
    'GND_V5':'(0,0,0,0,0,V5)';$S;
    'GND_V11':'(0,0,0,0,0,V11)';$S;
    'GND_V12':'(0,0,0,0,0,V12)';$S;
    'GND_V14':'(0,0,0,0,0,V14)';$S;
    'GND_V15':'(0,0,0,0,0,V15)';$S;
    'GND_V16':'(0,0,0,0,0,V16)';$S;
    'GND_V17':'(0,0,0,0,0,V17)';$S;
    'GND_V18':'(0,0,0,0,0,V18)';$S;
    'GND_V19':'(0,0,0,0,0,V19)';$S;
    'GND_W5':'(0,0,0,0,0,W5)';$S;
    'GND_W6':'(0,0,0,0,0,W6)';$S;
    'GND_W8':'(0,0,0,0,0,W8)';$S;
    'GND_W9':'(0,0,0,0,0,W9)';$S;
    'GND_W10':'(0,0,0,0,0,W10)';$S;
    'GND_W11':'(0,0,0,0,0,W11)';$S;
    'GND_W12':'(0,0,0,0,0,W12)';$S;
    'GND_L18':'(0,0,0,0,0,L18)';$S;
    'GND_L19':'(0,0,0,0,0,L19)';$S;
    'GND_L25':'(0,0,0,0,0,L25)';$S;
    'GND_M4':'(0,0,0,0,0,M4)';$S;
    'GND_M9':'(0,0,0,0,0,M9)';$S;
    'GND_M10':'(0,0,0,0,0,M10)';$S;
    'GND_M12':'(0,0,0,0,0,M12)';$S;
    'GND_M15':'(0,0,0,0,0,M15)';$S;
    'GND_M16':'(0,0,0,0,0,M16)';$S;
    'GND_M17':'(0,0,0,0,0,M17)';$S;
    'GND_W22':'(0,0,0,0,0,W22)';$S;
    'GND_W25':'(0,0,0,0,0,W25)';$S;
    'GND_Y6':'(0,0,0,0,0,Y6)';$S;
    'GND_Y22':'(0,0,0,0,0,Y22)';$S;
    'GND_AA1':'(0,0,0,0,0,AA1)';$S;
    'GND_AA3':'(0,0,0,0,0,AA3)';$S;
    'GND_AA8':'(0,0,0,0,0,AA8)';$S;
    'GND_AA7':'(0,0,0,0,0,AA7)';$S;
    'GND_AA6':'(0,0,0,0,0,AA6)';$S;
    'GND_M18':'(0,0,0,0,0,M18)';$S;
    'GND_M19':'(0,0,0,0,0,M19)';$S;
    'GND_N2':'(0,0,0,0,0,N2)';$S;
    'GND_N6':'(0,0,0,0,0,N6)';$S;
    'GND_N9':'(0,0,0,0,0,N9)';$S;
    'GND_N10':'(0,0,0,0,0,N10)';$S;
    'GND_N15':'(0,0,0,0,0,N15)';$S;
    'GND_N16':'(0,0,0,0,0,N16)';$S;
    'GND_N17':'(0,0,0,0,0,N17)';$S;
    'GND_N18':'(0,0,0,0,0,N18)';$S;
    'GND_N19':'(0,0,0,0,0,N19)';$S;
    'GND_AA10':'(0,0,0,0,0,AA10)';$S;
    'GND_AA14':'(0,0,0,0,0,AA14)';$S;
    'GND_AA15':'(0,0,0,0,0,AA15)';$S;
    'GND_AA19':'(0,0,0,0,0,AA19)';$S;
    'GND_AA22':'(0,0,0,0,0,AA22)';$S;
    'GND_AC2':'(0,0,0,0,0,AC2)';$S;
    'GND_AC6':'(0,0,0,0,0,AC6)';$S;
    'GND_AC25':'(0,0,0,0,0,AC25)';$S;
    'GND_AD1':'(0,0,0,0,0,AD1)';$S;
    'GND_AD4':'(0,0,0,0,0,AD4)';$S;
    'GND_AE3':'(0,0,0,0,0,AE3)';$S;
    'GND_AE6':'(0,0,0,0,0,AE6)';$S;
    'GND_AE9':'(0,0,0,0,0,AE9)';$S;
    'GND_AE13':'(0,0,0,0,0,AE13)';$S;
    'GND_AE17':'(0,0,0,0,0,AE17)';$S;
    'GND_AE20':'(0,0,0,0,0,AE20)';$S;
    'GND_AE23':'(0,0,0,0,0,AE23)';$S;
    'GND_AF1':'(0,0,0,0,0,AF1)';$S;
    'GND_AF4':'(0,0,0,0,0,AF4)';$S;
    'GND_AF26':'(0,0,0,0,0,AF26)';$S;
    'GND_P4':'(0,0,0,0,0,P4)';$S;
    'GND_P9':'(0,0,0,0,0,P9)';$S;
    'GND_P10':'(0,0,0,0,0,P10)';$S;
    'GND_P15':'(0,0,0,0,0,P15)';$S;
    'GND_P16':'(0,0,0,0,0,P16)';$S;
    'GND_P17':'(0,0,0,0,0,P17)';$S;
    'GND_P18':'(0,0,0,0,0,P18)';$S;
    'GND_P19':'(0,0,0,0,0,P19)';$S;
    'GND_AA20':'(0,0,0,0,0,AA20)';$S;
    'GND_U23':'(0,0,0,0,0,U23)';$S;
end_primitive;
primitive 'BAS70057F-BAS70-05-7-F,SMLF,ICA';body 'BAS70057F';
    'A':'(2)';IN;
    'B':'(1)';IN;
    'C':'(3)';BIDI;
end_primitive;
primitive 'BAT54C-BAT54C,SMLF,IC,BCBAT54CA';body 'BAT54C';
    'A':'(2)';IN;
    'B':'(1)';IN;
    'C':'(3)';BIDI;
end_primitive;
primitive 'BZA462A-BZA462A,SMLF,EMPTY,BCZA';body 'BZA462A';
    '2':'(2)';BIDI;
    '5':'(5)';BIDI;
    '1':'(1)';BIDI;
    '3':'(3)';BIDI;
    '4':'(4)';BIDI;
    '6':'(6)';BIDI;
end_primitive;
primitive 'CONN8_210HP1080BR1-CONN8_210-HA';body 'CONN8_210HP1080BR1';
    '1':'(1)';BIDI;
    '2':'(2)';BIDI;
    '3':'(3)';BIDI;
    '4':'(4)';BIDI;
    '5':'(5)';BIDI;
    '6':'(6)';BIDI;
    '7':'(7)';BIDI;
    '8':'(8)';BIDI;
end_primitive;
primitive 'CONN8_TSW10407FD-CONN8_TSW-104A';body 'CONN8_TSW10407FD';
    '5':'(5)';BIDI;
    '6':'(6)';BIDI;
    '7':'(7)';BIDI;
    '8':'(8)';BIDI;
    '3':'(3)';BIDI;
    '1':'(1)';BIDI;
    '4':'(4)';BIDI;
    '2':'(2)';BIDI;
end_primitive;
primitive 'CONN9_GSB3111315HR-CONN9_GSB31A';body 'CONN9_GSB3111315HR';
    'VBUS':'(1)';
    'GND':'(4)';
    'G1':'(G1)';
    'G2':'(G2)';
    'SSTX+':'(9)';IN;
    'SSTX-':'(8)';IN;
    'D-':'(2)';BIDI;
    'D+':'(3)';BIDI;
    'SSRX+':'(6)';OUT;
    'GND_D':'(7)';
    'SSRX-':'(5)';OUT;
end_primitive;
primitive 'DIODE_BIDIRECTIONAL-UCLAMP0511A';body 'DIODE_BIDIRECTIONAL';
    'A':'(A)';BIDI;
    'C':'(C)';BIDI;
end_primitive;
primitive 'DT1240E04LP7-DT1240E-04LP-7,SMA';body 'DT1240E04LP7';
    'IO1':'(1)';BIDI;
    'VSS1':'(3)';
    'IO3':'(4)';BIDI;
    'NC1':'(6)';OUT;
    'VSS2':'(8)';
    'NC3':'(9)';OUT;
    'NC4':'(10)';OUT;
    'IO2':'(2)';BIDI;
    'IO4':'(5)';BIDI;
    'NC2':'(7)';OUT;
end_primitive;
primitive 'DUMMY_SYMBOL-BIOS_FLASH,MECH,MA';body 'DUMMY_SYMBOL';
    '1':'(1)';OUT;
end_primitive;
primitive 'DUMMY_SYMBOL-BMC_FLASH,MECH,EMA';body 'DUMMY_SYMBOL';
    '1':'(1)';OUT;
end_primitive;
primitive 'FCONN168_ME1016810202011_SCM-FA';body 'FCONN168_ME1016810202011_SCM';
    'P12V_AUX_OA1':'(OA1)';
    'P12V_AUX_OA2':'(OA2)';
    'GND_OA3':'(OA3)';
    'GND_OA4':'(OA4)';
    'I3C_0_SCL':'(OA5)';BIDI;
    'I3C_0_SDA':'(OA6)';BIDI;
    'I3C_1_SCL':'(OA7)';BIDI;
    'I3C_1_SDA':'(OA8)';BIDI;
    'I3C_2_SCL':'(OA9)';BIDI;
    'I3C_2_SDA':'(OA10)';BIDI;
    'I3C_3_SCL':'(OA11)';BIDI;
    'I3C_3_SDA':'(OA12)';BIDI;
    'GND_OA13':'(OA13)';
    'VIRTUAL_RESEAT':'(OA14)';BIDI;
    'I2C_0_SCL':'(A1)';BIDI;
    'I2C_0_SDA':'(A2)';BIDI;
    'I2C_1_SCL':'(A3)';BIDI;
    'I2C_1_SDA':'(A4)';BIDI;
    'I2C_2_SCL':'(A5)';BIDI;
    'I2C_2_SDA':'(A6)';BIDI;
    'I2C_3_SCL':'(A7)';BIDI;
    'I2C_3_SDA':'(A8)';BIDI;
    'I2C_4_SCL':'(A9)';BIDI;
    'I2C_4_SDA':'(A10)';BIDI;
    'I2C_5_SCL':'(A11)';BIDI;
    'I2C_5_SDA':'(A12)';BIDI;
    'GND_A13':'(A13)';
    'CLK_100M_PCIE_DP':'(A14)';BIDI;
    'CLK_100M_PCIE_DN':'(A15)';BIDI;
    'GND_A16':'(A16)';
    'PCIE_BMC_TX_DP':'(A17)';BIDI;
    'PCIE_BMC_TX_DN':'(A18)';BIDI;
    'GND_A19':'(A19)';
    'PCIE_BMC_RX_DP':'(A20)';BIDI;
    'PCIE_BMC_RX_DN':'(A21)';BIDI;
    'GND_A22':'(A22)';
    'I2C_6_SCL':'(A23)';BIDI;
    'I2C_6_SDA':'(A24)';BIDI;
    'I2C_7_SCL':'(A25)';BIDI;
    'I2C_7_SDA':'(A26)';BIDI;
    'I2C_8_SCL':'(A27)';BIDI;
    'I2C_8_SDA':'(A28)';BIDI;
    'I2C_9_SCL':'(A29)';BIDI;
    'I2C_9_SDA':'(A30)';BIDI;
    'I2C_10_SCL':'(A31)';BIDI;
    'I2C_10_SDA':'(A32)';BIDI;
    'GND_A33':'(A33)';
    'JTAG_TCK':'(A34)';BIDI;
    'JTAG_TMS':'(A35)';BIDI;
    'JTAG_TDI':'(A36)';BIDI;
    'JTAG_TDO':'(A37)';BIDI;
    'I2C_11_SCL':'(A38)';BIDI;
    'I2C_11_SDA':'(A39)';BIDI;
    'I2C_12_SCL':'(A40)';BIDI;
    'I2C_12_SDA':'(A41)';BIDI;
    'GND_A42':'(A42)';
    'HPM_FW_RECOVERY':'(A43)';BIDI;
    'HPM_STBY_RDY':'(A44)';BIDI;
    'HPM_STBY_EN':'(A45)';BIDI;
    'HPM_STBY_RST_N':'(A46)';BIDI;
    'SYS_PWRBTN_N':'(A47)';BIDI;
    'SYS_PWROK':'(A48)';BIDI;
    'DBP_PREQ_N':'(A49)';BIDI;
    'DBP_PRDY_N':'(A50)';BIDI;
    'RST_PLTRST_BUF_N':'(A51)';BIDI;
    'SPARE1':'(A52)';BIDI;
    'ROT_CPU_RST_N':'(A53)';BIDI;
    'CHASI_N':'(A54)';BIDI;
    'SPARE0':'(A55)';BIDI;
    'IRQ_N':'(A56)';BIDI;
    'PRSNT1_N':'(A57)';BIDI;
    'GND_A58':'(A58)';
    'PCIE_HPM_RXP_0':'(A59)';BIDI;
    'PCIE_HPM_RXN_0':'(A60)';BIDI;
    'GND_A61':'(A61)';
    'PCIE_HPM_RXP_1':'(A62)';BIDI;
    'PCIE_HPM_RXN_1':'(A63)';BIDI;
    'GND_A64':'(A64)';
    'PCIE_HPM_RXP_2':'(A65)';BIDI;
    'PCIE_HPM_RXN_2':'(A66)';BIDI;
    'GND_A67':'(A67)';
    'PCIE_HPM_RXP_3':'(A68)';BIDI;
    'PCIE_HPM_RXN_3':'(A69)';BIDI;
    'GND_A70':'(A70)';
    'P12V_AUX_OB1':'(OB1)';
    'P12V_AUX_OB2':'(OB2)';
    'PRSNT0_N':'(OB3)';BIDI;
    'GND_OB4':'(OB4)';
    'UART1_SCM_TX':'(OB5)';BIDI;
    'UART1_SCM_RX':'(OB6)';BIDI;
    'GND_OB7':'(OB7)';
    'UART0_SCM_TX':'(OB8)';BIDI;
    'UART0_SCM_RX':'(OB9)';BIDI;
    'GND_OB10':'(OB10)';
    'SPI0_CLK':'(OB11)';BIDI;
    'SPI0_CS_N':'(OB12)';BIDI;
    'SPI0_MOSI':'(OB13)';BIDI;
    'SPI0_MISO':'(OB14)';BIDI;
    'ESPI_CLK':'(B1)';BIDI;
    'ESPI_CS0_N':'(B2)';BIDI;
    'ESPI_ALERT_N':'(B3)';BIDI;
    'ESPI_RESET_N':'(B4)';BIDI;
    'ESPI_IO0':'(B5)';BIDI;
    'ESPI_IO1':'(B6)';BIDI;
    'ESPI_IO2':'(B7)';BIDI;
    'ESPI_IO3':'(B8)';BIDI;
    'RSVD3':'(B9)';BIDI;
    'GND_B10':'(B10)';
    'QSPI0_CLK':'(B11)';BIDI;
    'QSPI0_CS0_N':'(B12)';BIDI;
    'QSPI0_D0':'(B13)';BIDI;
    'QSPI0_D1':'(B14)';BIDI;
    'QSPI0_D2':'(B15)';BIDI;
    'QSPI0_D3':'(B16)';BIDI;
    'GND_B17':'(B17)';
    'NCSI_CLK':'(B18)';BIDI;
    'NCSI_CRS_DV':'(B19)';BIDI;
    'NCSI_TXEN':'(B20)';BIDI;
    'NCSI_TXD0':'(B21)';BIDI;
    'NCSI_TXD1':'(B22)';BIDI;
    'NCSI_RXER':'(B23)';BIDI;
    'NCSI_RXD0':'(B24)';BIDI;
    'NCSI_RXD1':'(B25)';BIDI;
    'GND_B26':'(B26)';
    'PECI_BMC':'(B27)';BIDI;
    'PVCCIO_PECI':'(B28)';
    'SGPIO0_DO':'(B29)';BIDI;
    'SGPIO_CLK':'(B30)';BIDI;
    'SGPIO0_DI':'(B31)';BIDI;
    'SGPIO0_LD':'(B32)';BIDI;
    'GND_B33':'(B33)';
    'SGPIO1_DO':'(B34)';BIDI;
    'RSVD2':'(B35)';OUT;
    'SGPIO1_DI':'(B36)';BIDI;
    'SGPIO1_LD':'(B37)';BIDI;
    'GND_B38':'(B38)';
    'SGPIO_RESET_N':'(B39)';BIDI;
    'SGPIO_INTR_N':'(B40)';BIDI;
    'P3V0_BAT':'(B41)';
    'QSPI0_CS1_N':'(B42)';BIDI;
    'QSPI1_CLK':'(B43)';BIDI;
    'QSPI1_CS0_N':'(B44)';BIDI;
    'QSPI1_D0':'(B45)';BIDI;
    'QSPI1_D1':'(B46)';BIDI;
    'QSPI1_D2':'(B47)';BIDI;
    'QSPI1_D3':'(B48)';BIDI;
    'GND_B49':'(B49)';
    'USB2_DP':'(B50)';BIDI;
    'USB2_DN':'(B51)';BIDI;
    'GND_B52':'(B52)';
    'USB1_DP':'(B53)';BIDI;
    'USB1_DN':'(B54)';BIDI;
    'GND_B55':'(B55)';
    'RSVD0':'(B56)';OUT;
    'RSVD1':'(B57)';OUT;
    'GND_B58':'(B58)';
    'PCIE_HPM_TXP_0':'(B59)';BIDI;
    'PCIE_HPM_TXN_0':'(B60)';BIDI;
    'GND_B61':'(B61)';
    'PCIE_HPM_TXP_1':'(B62)';BIDI;
    'PCIE_HPM_TXN_1':'(B63)';BIDI;
    'GND_B64':'(B64)';
    'PCIE_HPM_TXP_2':'(B65)';BIDI;
    'PCIE_HPM_TXN_2':'(B66)';BIDI;
    'GND_B67':'(B67)';
    'PCIE_HPM_TXP_3':'(B68)';BIDI;
    'PCIE_HPM_TXN_3':'(B69)';BIDI;
    'GND_B70':'(B70)';
end_primitive;
primitive 'FSA3357K8X-FSA3357K8X,SMLF,IC,A';body 'FSA3357K8X';
    'A':'(7)';BIDI;
    'GND':'(4)';
    'B2':'(3)';BIDI;
    'S2':'(5)';IN;
    'VCC':'(8)';
    'B1':'(2)';BIDI;
    'B0':'(1)';BIDI;
    'S1':'(6)';IN;
end_primitive;
primitive 'HOLE_TH-EMPTY,DUMMY50';body 'HOLE';
    '1':'(1)';BIDI;
end_primitive;
primitive 'HOLE_TH-EMPTY,HOLE1211';body 'HOLE';
    '1':'(1)';BIDI;
end_primitive;
primitive 'HOLE_TH-EMPTY,HOLE1247';body 'HOLE';
    '1':'(1)';BIDI;
end_primitive;
primitive 'HOLE_TH-EMPTY,HOLE1248';body 'HOLE';
    '1':'(1)';BIDI;
end_primitive;
primitive 'HOLE_TH-EMPTY,HOLE620';body 'HOLE';
    '1':'(1)';BIDI;
end_primitive;
primitive 'HOLE_TH-EMPTY,TMP-C_HOLE8';body 'HOLE';
    '1':'(1)';BIDI;
end_primitive;
primitive 'IDTQS3VH257PAG_SMLF-IDTQS3VH25A';body 'IDTQS3VH257PAG';
    'YA':'(4)';BIDI;
    'YB':'(7)';BIDI;
    'YC':'(9)';BIDI;
    'YD':'(12)';BIDI;
    'S':'(1)';IN;
    'E*':'(15)';IN;
    'I_0A':'(2)';BIDI;
    'I_1A':'(3)';BIDI;
    'I_1B':'(6)';BIDI;
    'I_0B':'(5)';BIDI;
    'I_1C':'(10)';BIDI;
    'I_0C':'(11)';BIDI;
    'I_0D':'(14)';BIDI;
    'I_1D':'(13)';BIDI;
    'GND':'(8)';
    'VCC':'(16)';
end_primitive;
primitive 'K4A8G165WCBCTD-K4A8G165WC-BCTDA';body 'K4A8G165WCBCTD';
    'A0':'(P3)';IN;
    'A1':'(P7)';IN;
    'A10||AP':'(M3)';IN;
    'A11':'(T2)';IN;
    'A12||BC_N':'(M7)';IN;
    'A13':'(T8)';IN;
    'A2':'(R3)';IN;
    'A3':'(N7)';IN;
    'A4':'(N3)';IN;
    'A5':'(P8)';IN;
    'A6':'(P2)';IN;
    'A7':'(R8)';IN;
    'A8':'(R2)';IN;
    'A9':'(R7)';IN;
    'ACT_N':'(L3)';IN;
    'ALERT_N':'(P9)';BIDI;
    'BA0':'(N2)';IN;
    'BA1':'(N8)';IN;
    'BG0':'(M2)';IN;
    'CAS_N||A15':'(M8)';IN;
    'CS_N':'(L7)';IN;
    'CKE':'(K2)';IN;
    'NC1':'(T7)';OUT;
    'ODT':'(K3)';IN;
    'RAS_N':'(L8)';IN;
    'VDD0':'(B3)';
    'VDD1':'(B9)';
    'VDD2':'(D1)';
    'VDD3':'(G7)';
    'VDD4':'(J1)';
    'VDD5':'(J9)';
    'VDD6':'(L1)';
    'VDD7':'(L9)';
    'VDD8':'(R1)';
    'VDD9':'(T9)';
    'VDDQ0':'(A1)';
    'VDDQ1':'(A9)';
    'VDDQ2':'(C1)';
    'VDDQ3':'(D9)';
    'VDDQ4':'(F2)';
    'VDDQ5':'(F8)';
    'VDDQ6':'(G1)';
    'VDDQ7':'(G9)';
    'VDDQ8':'(J2)';
    'VDDQ9':'(J8)';
    'VPP0':'(B1)';
    'VPP1':'(R9)';
    'WE_N||A14':'(L2)';IN;
    'ZQ':'(F9)';
    'DQL0':'(G2)';BIDI;
    'DQL1':'(F7)';BIDI;
    'DQL2':'(H3)';BIDI;
    'DQL3':'(H7)';BIDI;
    'DQL4':'(H2)';BIDI;
    'DQL5':'(H8)';BIDI;
    'DQL6':'(J3)';BIDI;
    'DQL7':'(J7)';BIDI;
    'DQU0':'(A3)';BIDI;
    'DQU1':'(B8)';BIDI;
    'DQU2':'(C3)';BIDI;
    'DQU3':'(C7)';BIDI;
    'DQU4':'(C2)';BIDI;
    'DQU5':'(C8)';BIDI;
    'DQU6':'(D3)';BIDI;
    'DQU7':'(D7)';BIDI;
    'CK_T':'(K7)';IN;
    'CK_C':'(K8)';IN;
    'DQSU_T':'(B7)';BIDI;
    'DQSU_C':'(A7)';BIDI;
    'DQSL_T':'(G3)';BIDI;
    'DQSL_C':'(F3)';BIDI;
    'TEN':'(N9)';IN;
    'PAR':'(T3)';IN;
    'VREFCA':'(M1)';
    'VSS0':'(B2)';
    'VSS1':'(E1)';
    'VSS2':'(E9)';
    'VSS3':'(G8)';
    'VSS4':'(K1)';
    'VSS5':'(K9)';
    'VSS6':'(M9)';
    'VSS7':'(N1)';
    'VSS8':'(T1)';
    'VSSQ0':'(A2)';
    'VSSQ1':'(A8)';
    'VSSQ2':'(C9)';
    'VSSQ3':'(D2)';
    'VSSQ4':'(D8)';
    'VSSQ5':'(E3)';
    'VSSQ6':'(E8)';
    'VSSQ7':'(F1)';
    'VSSQ8':'(H1)';
    'VSSQ9':'(H9)';
    'DML_N||DBIL_N':'(E7)';BIDI;
    'DMU_N||DBIU_N':'(E2)';BIDI;
    'RESET_N':'(P1)';IN;
end_primitive;
primitive 'LCMXO3LF2100C5BG256C-LCMXO3LF-A';body 'LCMXO3LF2100C5BG256C';
    'VCCIO0_D5':'(D5,0,0,0,0,0,0)';$S;
    'VCCIO0_D12':'(D12,0,0,0,0,0,0)';$S;
    'VCCIO0_G8':'(G8,0,0,0,0,0,0)';$S;
    'VCCIO0_G9':'(G9,0,0,0,0,0,0)';$S;
    'PT9A':'(C4,0,0,0,0,0,0)';$S;BIDI;
    'PT9B':'(B5,0,0,0,0,0,0)';$S;BIDI;
    'PT9C':'(B3,0,0,0,0,0,0)';$S;BIDI;
    'PT10A':'(A4,0,0,0,0,0,0)';$S;BIDI;
    'PT10B':'(C5,0,0,0,0,0,0)';$S;BIDI;
    'PT11A':'(A5,0,0,0,0,0,0)';$S;BIDI;
    'PT11B':'(B6,0,0,0,0,0,0)';$S;BIDI;
    'PT11C':'(A3,0,0,0,0,0,0)';$S;BIDI;
    'PT11D':'(B4,0,0,0,0,0,0)';$S;BIDI;
    'PT12A':'(D6,0,0,0,0,0,0)';$S;BIDI;
    'PT12B':'(E7,0,0,0,0,0,0)';$S;BIDI;
    'PT12C||TDO':'(C6,0,0,0,0,0,0)';$S;BIDI;
    'PT12D||TDI':'(A6,0,0,0,0,0,0)';$S;BIDI;
    'PT13A':'(B7,0,0,0,0,0,0)';$S;BIDI;
    'PT13B':'(C7,0,0,0,0,0,0)';$S;BIDI;
    'PT13C':'(E6,0,0,0,0,0,0)';$S;BIDI;
    'PT13D':'(D7,0,0,0,0,0,0)';$S;BIDI;
    'PT16A':'(F7,0,0,0,0,0,0)';$S;BIDI;
    'PT16B':'(E8,0,0,0,0,0,0)';$S;BIDI;
    'PT16C||TCK':'(A7,0,0,0,0,0,0)';$S;BIDI;
    'PT16D||TMS':'(B8,0,0,0,0,0,0)';$S;BIDI;
    'PT17A||PCLKT0_1':'(C8,0,0,0,0,0,0)';$S;BIDI;
    'PT17B||PCLKC0_1':'(A8,0,0,0,0,0,0)';$S;BIDI;
    'PT17C':'(D8,0,0,0,0,0,0)';$S;BIDI;
    'PT17D':'(E9,0,0,0,0,0,0)';$S;BIDI;
    'PT18B':'(D9,0,0,0,0,0,0)';$S;BIDI;
    'PT18C||SCL||PCLKT0_0':'(A9,0,0,0,0,0,0)';$S;BIDI;
    'PT18D||SDA||PCLKC0_0':'(C9,0,0,0,0,0,0)';$S;BIDI;
    'PT19A':'(B9,0,0,0,0,0,0)';$S;BIDI;
    'PT19B':'(A10,0,0,0,0,0,0)';$S;BIDI;
    'PT19C':'(F9,0,0,0,0,0,0)';$S;BIDI;
    'PT19D':'(E11,0,0,0,0,0,0)';$S;BIDI;
    'PT20A':'(D10,0,0,0,0,0,0)';$S;BIDI;
    'PT20B':'(E10,0,0,0,0,0,0)';$S;BIDI;
    'PT20C||JTAGENB':'(C10,0,0,0,0,0,0)';$S;BIDI;
    'PT20D||PROGRAMN':'(B10,0,0,0,0,0,0)';$S;BIDI;
    'PT21A':'(A11,0,0,0,0,0,0)';$S;BIDI;
    'PT21B':'(C11,0,0,0,0,0,0)';$S;BIDI;
    'PT21C':'(F10,0,0,0,0,0,0)';$S;BIDI;
    'PT21D':'(D11,0,0,0,0,0,0)';$S;BIDI;
    'PT22A':'(B11,0,0,0,0,0,0)';$S;BIDI;
    'PT22B':'(A12,0,0,0,0,0,0)';$S;BIDI;
    'PT22C':'(B13,0,0,0,0,0,0)';$S;BIDI;
    'PT22D':'(A14,0,0,0,0,0,0)';$S;BIDI;
    'PT23A':'(C12,0,0,0,0,0,0)';$S;BIDI;
    'PT23B':'(B12,0,0,0,0,0,0)';$S;BIDI;
    'PT24A':'(B14,0,0,0,0,0,0)';$S;BIDI;
    'PT24B':'(A15,0,0,0,0,0,0)';$S;BIDI;
    'PT24C||INITN':'(A13,0,0,0,0,0,0)';$S;BIDI;
    'PT24D||DONE':'(C13,0,0,0,0,0,0)';$S;BIDI;
    'PT18A':'(F8,0,0,0,0,0,0)';$S;BIDI;
    'PR10C':'(0,J11,0,0,0,0,0)';$S;BIDI;
    'PR10D':'(0,L12,0,0,0,0,0)';$S;BIDI;
    'PR6A':'(0,G16,0,0,0,0,0)';$S;BIDI;
    'PR6B':'(0,H15,0,0,0,0,0)';$S;BIDI;
    'PR12C':'(0,K11,0,0,0,0,0)';$S;BIDI;
    'PR12D':'(0,L13,0,0,0,0,0)';$S;BIDI;
    'PR7A||PCLKT1_0':'(0,H14,0,0,0,0,0)';$S;BIDI;
    'PR7B||PCLKC1_0':'(0,H16,0,0,0,0,0)';$S;BIDI;
    'PR13C':'(0,N15,0,0,0,0,0)';$S;BIDI;
    'PR13D':'(0,P16,0,0,0,0,0)';$S;BIDI;
    'PR14A':'(0,N16,0,0,0,0,0)';$S;BIDI;
    'PR14B':'(0,N14,0,0,0,0,0)';$S;BIDI;
    'PR14C':'(0,P15,0,0,0,0,0)';$S;BIDI;
    'PR14D':'(0,R16,0,0,0,0,0)';$S;BIDI;
    'PR13A':'(0,M14,0,0,0,0,0)';$S;BIDI;
    'PR13B':'(0,M15,0,0,0,0,0)';$S;BIDI;
    'PR12A':'(0,L15,0,0,0,0,0)';$S;BIDI;
    'PR12B':'(0,M16,0,0,0,0,0)';$S;BIDI;
    'PR11C':'(0,K13,0,0,0,0,0)';$S;BIDI;
    'PR11D':'(0,K12,0,0,0,0,0)';$S;BIDI;
    'PR11A':'(0,L16,0,0,0,0,0)';$S;BIDI;
    'PR11B':'(0,L14,0,0,0,0,0)';$S;BIDI;
    'PR10A':'(0,K14,0,0,0,0,0)';$S;BIDI;
    'PR10B':'(0,K15,0,0,0,0,0)';$S;BIDI;
    'PR9A':'(0,J15,0,0,0,0,0)';$S;BIDI;
    'PR9B':'(0,K16,0,0,0,0,0)';$S;BIDI;
    'PR1A':'(0,D14,0,0,0,0,0)';$S;BIDI;
    'PR1B':'(0,E15,0,0,0,0,0)';$S;BIDI;
    'PR1C':'(0,C15,0,0,0,0,0)';$S;BIDI;
    'PR1D':'(0,B16,0,0,0,0,0)';$S;BIDI;
    'PR2A':'(0,D16,0,0,0,0,0)';$S;BIDI;
    'PR2B':'(0,E14,0,0,0,0,0)';$S;BIDI;
    'PR2C':'(0,C16,0,0,0,0,0)';$S;BIDI;
    'PR2D':'(0,D15,0,0,0,0,0)';$S;BIDI;
    'PR3C':'(0,F13,0,0,0,0,0)';$S;BIDI;
    'PR3D':'(0,G12,0,0,0,0,0)';$S;BIDI;
    'PR4C':'(0,F12,0,0,0,0,0)';$S;BIDI;
    'PR4D':'(0,G13,0,0,0,0,0)';$S;BIDI;
    'PR3A':'(0,E16,0,0,0,0,0)';$S;BIDI;
    'PR3B':'(0,F15,0,0,0,0,0)';$S;BIDI;
    'PR5C':'(0,G11,0,0,0,0,0)';$S;BIDI;
    'PR5D':'(0,H12,0,0,0,0,0)';$S;BIDI;
    'PR4A':'(0,F14,0,0,0,0,0)';$S;BIDI;
    'PR4B':'(0,F16,0,0,0,0,0)';$S;BIDI;
    'PR6C':'(0,H13,0,0,0,0,0)';$S;BIDI;
    'PR6D':'(0,J12,0,0,0,0,0)';$S;BIDI;
    'PR7C':'(0,J16,0,0,0,0,0)';$S;BIDI;
    'PR7D':'(0,J14,0,0,0,0,0)';$S;BIDI;
    'PR9C':'(0,H11,0,0,0,0,0)';$S;BIDI;
    'PR9D':'(0,J13,0,0,0,0,0)';$S;BIDI;
    'PR5A':'(0,G15,0,0,0,0,0)';$S;BIDI;
    'PR5B':'(0,G14,0,0,0,0,0)';$S;BIDI;
    'VCCIO1_M13':'(0,M13,0,0,0,0,0)';$S;
    'VCCIO1_J10':'(0,J10,0,0,0,0,0)';$S;
    'VCCIO1_E13':'(0,E13,0,0,0,0,0)';$S;
    'VCCIO1_H10':'(0,H10,0,0,0,0,0)';$S;
    'PB9C':'(0,0,M7,0,0,0,0)';$S;BIDI;
    'PB9D':'(0,0,N7,0,0,0,0)';$S;BIDI;
    'PB11C':'(0,0,M6,0,0,0,0)';$S;BIDI;
    'PB11D':'(0,0,L8,0,0,0,0)';$S;BIDI;
    'PB11A||PCLKT2_0':'(0,0,T7,0,0,0,0)';$S;BIDI;
    'PB11B||PCLKC2_0':'(0,0,R8,0,0,0,0)';$S;BIDI;
    'PB12A':'(0,0,P8,0,0,0,0)';$S;BIDI;
    'PB12B':'(0,0,T8,0,0,0,0)';$S;BIDI;
    'PB12C':'(0,0,N8,0,0,0,0)';$S;BIDI;
    'PB12D':'(0,0,L9,0,0,0,0)';$S;BIDI;
    'PB16C':'(0,0,M8,0,0,0,0)';$S;BIDI;
    'PB16D':'(0,0,N9,0,0,0,0)';$S;BIDI;
    'PB16A||PCLKT2_1':'(0,0,T9,0,0,0,0)';$S;BIDI;
    'PB16B||PCLKC2_1':'(0,0,P9,0,0,0,0)';$S;BIDI;
    'PB18A':'(0,0,R9,0,0,0,0)';$S;BIDI;
    'PB18B':'(0,0,T10,0,0,0,0)';$S;BIDI;
    'PB18C':'(0,0,M9,0,0,0,0)';$S;BIDI;
    'PB18D':'(0,0,L10,0,0,0,0)';$S;BIDI;
    'PB19C':'(0,0,N10,0,0,0,0)';$S;BIDI;
    'PB19D':'(0,0,M11,0,0,0,0)';$S;BIDI;
    'PB19A':'(0,0,P10,0,0,0,0)';$S;BIDI;
    'PB19B':'(0,0,R10,0,0,0,0)';$S;BIDI;
    'PB21A':'(0,0,T11,0,0,0,0)';$S;BIDI;
    'PB21B':'(0,0,P11,0,0,0,0)';$S;BIDI;
    'PB21C':'(0,0,M10,0,0,0,0)';$S;BIDI;
    'PB21D':'(0,0,N11,0,0,0,0)';$S;BIDI;
    'PB22C':'(0,0,R13,0,0,0,0)';$S;BIDI;
    'PB22D':'(0,0,T14,0,0,0,0)';$S;BIDI;
    'PB22A':'(0,0,R11,0,0,0,0)';$S;BIDI;
    'PB22B':'(0,0,T12,0,0,0,0)';$S;BIDI;
    'PB24A':'(0,0,P12,0,0,0,0)';$S;BIDI;
    'PB24B':'(0,0,T13,0,0,0,0)';$S;BIDI;
    'PB25A||SN':'(0,0,R12,0,0,0,0)';$S;BIDI;
    'PB25B||SI||SISPI':'(0,0,P13,0,0,0,0)';$S;BIDI;
    'PB25C':'(0,0,T15,0,0,0,0)';$S;BIDI;
    'PB25D':'(0,0,R14,0,0,0,0)';$S;BIDI;
    'PB3A':'(0,0,P4,0,0,0,0)';$S;BIDI;
    'PB3B':'(0,0,T4,0,0,0,0)';$S;BIDI;
    'PB3C':'(0,0,T2,0,0,0,0)';$S;BIDI;
    'PB3D':'(0,0,R3,0,0,0,0)';$S;BIDI;
    'PB5A||CSSPIN':'(0,0,R5,0,0,0,0)';$S;BIDI;
    'PB5B':'(0,0,P5,0,0,0,0)';$S;BIDI;
    'PB6C':'(0,0,T3,0,0,0,0)';$S;BIDI;
    'PB6D':'(0,0,R4,0,0,0,0)';$S;BIDI;
    'PB6A':'(0,0,T5,0,0,0,0)';$S;BIDI;
    'PB6B':'(0,0,R6,0,0,0,0)';$S;BIDI;
    'PB8C':'(0,0,N6,0,0,0,0)';$S;BIDI;
    'PB8D':'(0,0,L7,0,0,0,0)';$S;BIDI;
    'PB8A||MCLK||CCLK':'(0,0,P6,0,0,0,0)';$S;BIDI;
    'PB8B||SO||SPISO':'(0,0,T6,0,0,0,0)';$S;BIDI;
    'PB9A':'(0,0,R7,0,0,0,0)';$S;BIDI;
    'PB9B':'(0,0,P7,0,0,0,0)';$S;BIDI;
    'VCCIO2_K8':'(0,0,K8,0,0,0,0)';$S;
    'VCCIO2_K9':'(0,0,K9,0,0,0,0)';$S;
    'VCCIO2_N12':'(0,0,N12,0,0,0,0)';$S;
    'VCCIO2_N5':'(0,0,N5,0,0,0,0)';$S;
    'PL11A':'(0,0,0,L1,0,0,0)';$S;BIDI;
    'PL11B':'(0,0,0,L3,0,0,0)';$S;BIDI;
    'PL11C':'(0,0,0,K4,0,0,0)';$S;BIDI;
    'PL11D':'(0,0,0,L5,0,0,0)';$S;BIDI;
    'PL12C':'(0,0,0,K5,0,0,0)';$S;BIDI;
    'PL12D':'(0,0,0,L4,0,0,0)';$S;BIDI;
    'PL12A||PCLKT3_0':'(0,0,0,L2,0,0,0)';$S;BIDI;
    'PL12B||PCLKC3_0':'(0,0,0,M1,0,0,0)';$S;BIDI;
    'PL14A':'(0,0,0,M2,0,0,0)';$S;BIDI;
    'PL14B':'(0,0,0,N3,0,0,0)';$S;BIDI;
    'PL14C':'(0,0,0,R1,0,0,0)';$S;BIDI;
    'PL14D':'(0,0,0,P2,0,0,0)';$S;BIDI;
    'VCCIO3':'(0,0,0,M4,0,0,0)';$S;
    'PL13C':'(0,0,0,N2,0,0,0)';$S;BIDI;
    'PL13D':'(0,0,0,P1,0,0,0)';$S;BIDI;
    'PL13A':'(0,0,0,M3,0,0,0)';$S;BIDI;
    'PL13B':'(0,0,0,N1,0,0,0)';$S;BIDI;
    'PL6A':'(0,0,0,0,G1,0,0)';$S;BIDI;
    'PL6B':'(0,0,0,0,H2,0,0)';$S;BIDI;
    'PL6C':'(0,0,0,0,H4,0,0)';$S;BIDI;
    'PL6D':'(0,0,0,0,J6,0,0)';$S;BIDI;
    'PL7A':'(0,0,0,0,H3,0,0)';$S;BIDI;
    'PL7B':'(0,0,0,0,H1,0,0)';$S;BIDI;
    'PL7C||PCLKT4_0':'(0,0,0,0,J1,0,0)';$S;BIDI;
    'PL7D||PCLKC4_0':'(0,0,0,0,J3,0,0)';$S;BIDI;
    'PL10C':'(0,0,0,0,J5,0,0)';$S;BIDI;
    'PL10D':'(0,0,0,0,K6,0,0)';$S;BIDI;
    'PL10A':'(0,0,0,0,K3,0,0)';$S;BIDI;
    'PL10B':'(0,0,0,0,K2,0,0)';$S;BIDI;
    'PL9A':'(0,0,0,0,J2,0,0)';$S;BIDI;
    'PL9B':'(0,0,0,0,K1,0,0)';$S;BIDI;
    'PL9C':'(0,0,0,0,H5,0,0)';$S;BIDI;
    'PL9D':'(0,0,0,0,J4,0,0)';$S;BIDI;
    'VCCIO4_H7':'(0,0,0,0,H7,0,0)';$S;
    'VCCIO4_J7':'(0,0,0,0,J7,0,0)';$S;
    'PL1C':'(0,0,0,0,0,B1,0)';$S;BIDI;
    'PL1D':'(0,0,0,0,0,C2,0)';$S;BIDI;
    'PL1A||L_GPLLT_FB':'(0,0,0,0,0,D3,0)';$S;BIDI;
    'PL1B||L_GPLLC_FB':'(0,0,0,0,0,D1,0)';$S;BIDI;
    'PL2A||L_GPLLT_IN':'(0,0,0,0,0,E2,0)';$S;BIDI;
    'PL2B||L_GPLLC_IN':'(0,0,0,0,0,E3,0)';$S;BIDI;
    'PL2C':'(0,0,0,0,0,C1,0)';$S;BIDI;
    'PL2D':'(0,0,0,0,0,D2,0)';$S;BIDI;
    'PL3A||PCLKT5_0':'(0,0,0,0,0,E1,0)';$S;BIDI;
    'PL3B||PCLKC5_0':'(0,0,0,0,0,F2,0)';$S;BIDI;
    'PL3C':'(0,0,0,0,0,F4,0)';$S;BIDI;
    'PL3D':'(0,0,0,0,0,G6,0)';$S;BIDI;
    'PL5A':'(0,0,0,0,0,G2,0)';$S;BIDI;
    'PL5B':'(0,0,0,0,0,G3,0)';$S;BIDI;
    'PL5C':'(0,0,0,0,0,F5,0)';$S;BIDI;
    'PL5D':'(0,0,0,0,0,H6,0)';$S;BIDI;
    'VCCIO5':'(0,0,0,0,0,E4,0)';$S;
    'PL4C':'(0,0,0,0,0,G5,0)';$S;BIDI;
    'PL4D':'(0,0,0,0,0,G4,0)';$S;BIDI;
    'PL4A':'(0,0,0,0,0,F3,0)';$S;BIDI;
    'PL4B':'(0,0,0,0,0,F1,0)';$S;BIDI;
    'GND_B2':'(0,0,0,0,0,0,B2)';$S;
    'GND_B15':'(0,0,0,0,0,0,B15)';$S;
    'GND_C3':'(0,0,0,0,0,0,C3)';$S;
    'GND_C14':'(0,0,0,0,0,0,C14)';$S;
    'GND_D4':'(0,0,0,0,0,0,D4)';$S;
    'GND_D13':'(0,0,0,0,0,0,D13)';$S;
    'GND_E5':'(0,0,0,0,0,0,E5)';$S;
    'GND_E12':'(0,0,0,0,0,0,E12)';$S;
    'GND_F6':'(0,0,0,0,0,0,F6)';$S;
    'GND_F11':'(0,0,0,0,0,0,F11)';$S;
    'GND_H8':'(0,0,0,0,0,0,H8)';$S;
    'GND_H9':'(0,0,0,0,0,0,H9)';$S;
    'GND_J8':'(0,0,0,0,0,0,J8)';$S;
    'GND_J9':'(0,0,0,0,0,0,J9)';$S;
    'GND_L6':'(0,0,0,0,0,0,L6)';$S;
    'GND_L11':'(0,0,0,0,0,0,L11)';$S;
    'GND_M5':'(0,0,0,0,0,0,M5)';$S;
    'GND_M12':'(0,0,0,0,0,0,M12)';$S;
    'GND_N4':'(0,0,0,0,0,0,N4)';$S;
    'GND_N13':'(0,0,0,0,0,0,N13)';$S;
    'GND_P3':'(0,0,0,0,0,0,P3)';$S;
    'GND_P14':'(0,0,0,0,0,0,P14)';$S;
    'GND_R2':'(0,0,0,0,0,0,R2)';$S;
    'GND_R15':'(0,0,0,0,0,0,R15)';$S;
    'NC1':'(0,0,0,0,0,0,A2)';$S;OUT;
    'VCC_T16':'(0,0,0,0,0,0,T16)';$S;
    'VCC_T1':'(0,0,0,0,0,0,T1)';$S;
    'VCC_K10':'(0,0,0,0,0,0,K10)';$S;
    'VCC_K7':'(0,0,0,0,0,0,K7)';$S;
    'VCC_G10':'(0,0,0,0,0,0,G10)';$S;
    'VCC_G7':'(0,0,0,0,0,0,G7)';$S;
    'VCC_A16':'(0,0,0,0,0,0,A16)';$S;
    'VCC_A1':'(0,0,0,0,0,0,A1)';$S;
end_primitive;
primitive 'M24128BWDW6TP-M24128-BWDW6TP,SA';body 'M24128BWDW6TP';
    'VCC':'(8)';
    'WC#':'(7)';IN;
    'SCL':'(6)';IN;
    'SDA':'(5)';BIDI;
    'VSS':'(4)';
    'E2':'(3)';IN;
    'E1':'(2)';IN;
    'E0':'(1)';IN;
end_primitive;
primitive 'MC74VHC1G07DFT2G-MC74VHC1G07DFA';body 'MC74VHC1G07DFT2G';
    'VCC':'(5)';
    'IN_A':'(2)';IN;
    'GND':'(3)';
    'OUT_Y':'(4)';OUT;
    'NC1':'(1)';OUT;
end_primitive;
primitive 'MC74VHC1G32DTT1G-MC74VHC1G32DTA';body 'MC74VHC1G32DTT1G';
    'OUT_Y':'(4)';OUT;
    'IN_B':'(1)';IN;
    'IN_A':'(2)';IN;
    'GND':'(3)';
    'VCC':'(5)';
end_primitive;
primitive 'ME_DUMMY_SYMBOL-PB-E1_SMALL,MEA';body 'ME_DUMMY_SYMBOL';
end_primitive;
primitive 'ME_DUMMY_SYMBOL-QUANTA_LOGO_7XA';body 'ME_DUMMY_SYMBOL';
end_primitive;
primitive 'ME_DUMMY_SYMBOL-SNLABEL_7X7,MEA';body 'ME_DUMMY_SYMBOL';
end_primitive;
primitive 'ME_DUMMY_SYMBOL-WEEE,MECH,EMPTA';body 'ME_DUMMY_SYMBOL';
end_primitive;
primitive 'MMBT39047F-MMBT3904-7-F,SMLF,IA';body 'MMBT39047F';
    '1':'(B)';IN;
    '2':'(E)';BIDI;
    '3':'(C)';BIDI;
end_primitive;
primitive 'MOSFET_DUAL_6P-2N7002KDW,SMLF,A';body 'MOSFET_DUAL_6P';
    'G1':'(2)';BIDI;
    'G2':'(5)';BIDI;
    'S1':'(1)';BIDI;
    'S2':'(4)';BIDI;
    'D1':'(6)';BIDI;
    'D2':'(3)';BIDI;
end_primitive;
primitive 'MOSFET_NCH_4D1S-NTGS4141NT1G,SA';body 'MOSFET_NCH_4D1S';
    '1':'(1)';BIDI;
    '6':'(6)';BIDI;
    '3':'(3)';IN;
    '2':'(2)';BIDI;
    '4':'(4)';BIDI;
    '5':'(5)';BIDI;
end_primitive;
primitive 'MOSFET_NCH_DUAL-2N7002KDW,SMLFA';body 'MOSFET_NCH_DUAL';
    'S1':'(1,0)';$S;BIDI;
    'G1':'(2,0)';$S;BIDI;
    'D1':'(6,0)';$S;BIDI;
    'D2':'(0,3)';$S;BIDI;
    'G2':'(0,5)';$S;BIDI;
    'S2':'(0,4)';$S;BIDI;
end_primitive;
primitive 'MOSFET_NCH_DUAL-PJT138K,SMLF,IA';body 'MOSFET_NCH_DUAL';
    'S1':'(1,0)';$S;BIDI;
    'G1':'(2,0)';$S;BIDI;
    'D1':'(6,0)';$S;BIDI;
    'D2':'(0,3)';$S;BIDI;
    'G2':'(0,5)';$S;BIDI;
    'S2':'(0,4)';$S;BIDI;
end_primitive;
primitive 'MOSFET_N_GSD-DMG6968U-7,SMLF,IA';body 'MOSFET_N_GSD';
    'GATE':'(G)';IN;
    'SOURCE':'(S)';BIDI;
    'DRAIN':'(D)';BIDI;
end_primitive;
primitive 'MOSFET_N_GSD-NX7002AK,SMLF,IC,A';body 'MOSFET_N_GSD';
    'GATE':'(G)';IN;
    'SOURCE':'(S)';BIDI;
    'DRAIN':'(D)';BIDI;
end_primitive;
primitive 'MOSFET_N_SMLF-BSS138K,BSS138K,A';body 'MOSFET_N';
    'GATE':'(G)';IN;
    'DRAIN':'(D)';OUT;
    'SOURCE':'(S)';BIDI;
end_primitive;
primitive 'MOSFET_PCH_GDS-NTR1P02LT1G,SMLA';body 'MOSFET_PCH_GDS';
    'D':'(D)';BIDI;
    'G':'(G)';IN;
    'S':'(S)';BIDI;
end_primitive;
primitive 'MPQ8626GDZ-MPQ8626GD-Z,SMLF,ICA';body 'MPQ8626GDZ';
    'VIN':'(3)';IN;
    'PGOOD':'(9)';OUT;
    'PGND2':'(14)';
    'EN':'(5)';IN;
    'BST':'(10)';IN;
    'FB':'(6)';IN;
    'AGND':'(7)';
    'VCC':'(13)';OUT;
    'PGND1':'(1)';
    'SW2':'(11)';OUT;
    'TRK_REF':'(8)';IN;
    'MODE':'(12)';IN;
    'CS':'(4)';IN;
    'SW1':'(2)';OUT;
end_primitive;
primitive 'MPQ8633AGLEC807Z-MPQ8633AGLE-CA';body 'MPQ8633AGLEC807Z';
    'VIN1':'(10)';IN;
    'PGOOD':'(9)';OUT;
    'PGND':'(11_18)';
    'EN':'(8)';IN;
    'BST':'(1)';IN;
    'FB':'(7)';IN;
    'AGND':'(2)';
    'VCC':'(19)';
    'RGND':'(6)';
    'SW':'(20)';OUT;
    'TRK_REF':'(5)';IN;
    'MODE':'(4)';IN;
    'CS':'(3)';IN;
    'VIN2':'(21)';IN;
end_primitive;
primitive 'MX25L51245GMI10G-MX25L51245GMIA';body 'MX25L51245GMI10G';
    'NC_SIO3':'(1)';BIDI;
    'VCC':'(2)';
    'RESET#':'(3)';BIDI;
    'NC1':'(4)';OUT;
    'DNU1':'(5)';OUT;
    'DNU2':'(6)';OUT;
    'CS#':'(7)';BIDI;
    'SO_SIO1':'(8)';BIDI;
    'WP#_SIO2':'(9)';BIDI;
    'GND':'(10)';
    'DNU3':'(11)';OUT;
    'DNU4':'(12)';OUT;
    'NC2':'(13)';OUT;
    'NC3':'(14)';OUT;
    'SI_SIO0':'(15)';BIDI;
    'SCLK':'(16)';IN;
end_primitive;
primitive 'NB695GDZ-NB695GD-Z,SMLF,IC,AL0A';body 'NB695GDZ';
    'VIN':'(1)';
    'PG':'(13)';OUT;
    'PGND':'(2)';
    'EN':'(5)';IN;
    'BST':'(9)';
    'AGND':'(11)';
    'LP#':'(6)';IN;
    'C1':'(3)';IN;
    'C0':'(4)';IN;
    'MODE':'(7)';IN;
    'VOUT':'(12)';
    'SW':'(8)';
    '3V3':'(10)';
end_primitive;
primitive 'NC7SB3157_SMLF-NC7SB3157P6X,NCA';body 'NC7SB3157';
    'B1':'(1)';BIDI;
    'GND':'(2)';
    'B0':'(3)';BIDI;
    'S':'(6)';IN;
    'VCC':'(5)';
    'A':'(4)';BIDI;
end_primitive;
primitive 'NCP380HSNAJAAT1G-NCP380HSNAJAAA';body 'NCP380HSNAJAAT1G';
    'FLAG_N':'(4)';OUT;
    'IN':'(1)';
    'ILIM':'(5)';IN;
    'OUT':'(6)';OUT;
    'EN':'(3)';IN;
    'GND':'(2)';
end_primitive;
primitive 'OSC4_7X25000018-25MHZ,SMLF,MISA';body 'OSC4_7X25000018';
    'OE':'(1)';IN;
    'GND':'(2)';
    'OUT':'(3)';OUT;
    'VDD':'(4)';
end_primitive;
primitive 'PCA9517ADP_SMLF-PCA9517ADP,IC,A';body 'PCA9517ADP';
    'ENABLE':'(5)';BIDI;
    'VCCB':'(8)';BIDI;
    'SCLA':'(2)';BIDI;
    'SDAA':'(3)';BIDI;
    'SDAB':'(6)';BIDI;
    'SCLB':'(7)';BIDI;
    'VCCA':'(1)';
    'GND':'(4)';
end_primitive;
primitive 'PCA9555PW_SMLF-PCA9555PW,IC,TMA';body 'PCA9555PW';
    'INT*':'(1)';OUT;
    'SDA':'(23)';BIDI;
    'SCL':'(22)';BIDI;
    'P00':'(4)';BIDI;
    'P01':'(5)';BIDI;
    'P02':'(6)';BIDI;
    'P03':'(7)';BIDI;
    'P04':'(8)';BIDI;
    'P05':'(9)';BIDI;
    'P06':'(10)';BIDI;
    'P07':'(11)';BIDI;
    'P10':'(13)';BIDI;
    'P11':'(14)';BIDI;
    'P12':'(15)';BIDI;
    'P13':'(16)';BIDI;
    'P14':'(17)';BIDI;
    'P15':'(18)';BIDI;
    'P16':'(19)';BIDI;
    'P17':'(20)';BIDI;
    'A0':'(21)';BIDI;
    'A1':'(2)';BIDI;
    'A2':'(3)';BIDI;
    'VDD':'(24)';
    'VSS':'(12)';
end_primitive;
primitive 'PI3PCIE3212ZBEX-PI3PCIE3212ZBEA';body 'PI3PCIE3212ZBEX';
    'VDD2':'(10)';
    'VDD1':'(6)';
    'VDD0':'(1)';
    'A0_P':'(3)';BIDI;
    'A0_N':'(4)';BIDI;
    'A1_P':'(7)';BIDI;
    'A1_N':'(8)';BIDI;
    'SEL':'(9)';IN;
    'B0_P':'(19)';BIDI;
    'B0_N':'(18)';BIDI;
    'B1_P':'(17)';BIDI;
    'B1_N':'(16)';BIDI;
    'C0_P':'(15)';BIDI;
    'C0_N':'(14)';BIDI;
    'C1_P':'(13)';BIDI;
    'C1_N':'(12)';BIDI;
    'TH':'(TH)';
    'GND2':'(11)';
    'GND1':'(5)';
    'GND0':'(20)';
    'PD':'(2)';IN;
end_primitive;
primitive 'PICOPROBE_BXA-DELTA-L 4.0,SMLFA';body 'PICOPROBE_BXA';
    '2_N':'(2)';
    '3_G':'(3)';
    '1_P':'(1)';
end_primitive;
primitive 'PRTR5V0U2X-PRTR5V0U2X,SMLF,IC,A';body 'PRTR5V0U2X';
    'IO1':'(2)';BIDI;
    'GND':'(1)';
    'VCC':'(4)';
    'IO2':'(3)';BIDI;
end_primitive;
primitive 'Q_CAP_0402-0.1UF,25V,10%,EMPTYA';body 'Q_CAP';
    'A':'(1)';
    'B':'(2)';
end_primitive;
primitive 'Q_CAP_0402-0.1UF,25V,10%,X7R,CA';body 'Q_CAP';
    'A':'(1)';
    'B':'(2)';
end_primitive;
primitive 'Q_CAP_0402-0.22UF,16V,10%,EMPTA';body 'Q_CAP';
    'A':'(1)';
    'B':'(2)';
end_primitive;
primitive 'Q_CAP_0402-0.22UF,16V,10%,X7R,A';body 'Q_CAP';
    'A':'(1)';
    'B':'(2)';
end_primitive;
primitive 'Q_CAP_0402-100PF,50V,5%,EMPTY,A';body 'Q_CAP';
    'A':'(1)';
    'B':'(2)';
end_primitive;
primitive 'Q_CAP_0402-100PF,50V,5%,NPO,CHA';body 'Q_CAP';
    'A':'(1)';
    'B':'(2)';
end_primitive;
primitive 'Q_CAP_0402-10PF,50V,1%,NPO,TMPA';body 'Q_CAP';
    'A':'(1)';
    'B':'(2)';
end_primitive;
primitive 'Q_CAP_0402-15PF,50V,5%,C0G,CH0A';body 'Q_CAP';
    'A':'(1)';
    'B':'(2)';
end_primitive;
primitive 'Q_CAP_0402-18PF,50V,5%,C0G,CH0A';body 'Q_CAP';
    'A':'(1)';
    'B':'(2)';
end_primitive;
primitive 'Q_CAP_0402-1UF,16V,10%,EMPTY,TA';body 'Q_CAP';
    'A':'(1)';
    'B':'(2)';
end_primitive;
primitive 'Q_CAP_0402-2200PF,50V,10%,X7R,A';body 'Q_CAP';
    'A':'(1)';
    'B':'(2)';
end_primitive;
primitive 'Q_CAP_0402-22PF,50V,5%,NPO,TMPA';body 'Q_CAP';
    'A':'(1)';
    'B':'(2)';
end_primitive;
primitive 'Q_CAP_0402-3300PF,50V,10%,X7R,A';body 'Q_CAP';
    'A':'(1)';
    'B':'(2)';
end_primitive;
primitive 'Q_CAP_0402-470PF,50V,10%,X7R,TA';body 'Q_CAP';
    'A':'(1)';
    'B':'(2)';
end_primitive;
primitive 'Q_CAP_0603-1UF,16V,10%,EMPTY,TA';body 'Q_CAP';
    'A':'(1)';
    'B':'(2)';
end_primitive;
primitive 'Q_CAP_0805-22UF,4V,20%,X6S,TMPA';body 'Q_CAP';
    'A':'(1)';
    'B':'(2)';
end_primitive;
primitive 'Q_CAP_C0402-0.001UF,50V,10%,EMA';body 'Q_CAP';
    'A':'(1)';
    'B':'(2)';
end_primitive;
primitive 'Q_CAP_C0402-0.01UF,50V,10%,EMPA';body 'Q_CAP';
    'A':'(1)';
    'B':'(2)';
end_primitive;
primitive 'Q_CAP_C0402-0.01UF,50V,10%,X7RA';body 'Q_CAP';
    'A':'(1)';
    'B':'(2)';
end_primitive;
primitive 'Q_CAP_C0402-10UF,6.3V,20%,X6S,A';body 'Q_CAP';
    'A':'(1)';
    'B':'(2)';
end_primitive;
primitive 'Q_CAP_C0402-1UF,25V,10%,EMPTY,A';body 'Q_CAP';
    'A':'(1)';
    'B':'(2)';
end_primitive;
primitive 'Q_CAP_C0402-1UF,25V,10%,X6S,CHA';body 'Q_CAP';
    'A':'(1)';
    'B':'(2)';
end_primitive;
primitive 'Q_CAP_C0402-2.2UF,10V,10%,X6S,A';body 'Q_CAP';
    'A':'(1)';
    'B':'(2)';
end_primitive;
primitive 'Q_CAP_C0402-4700P,25V,10%,EMPTA';body 'Q_CAP';
    'A':'(1)';
    'B':'(2)';
end_primitive;
primitive 'Q_CAP_C0402-68PF,50V,5%,COG,CHA';body 'Q_CAP';
    'A':'(1)';
    'B':'(2)';
end_primitive;
primitive 'Q_CAP_C0603-10UF,16V,20%,X6S,CA';body 'Q_CAP';
    'A':'(1)';
    'B':'(2)';
end_primitive;
primitive 'Q_CAP_C0603-22UF,10V,20%,EMPTYA';body 'Q_CAP';
    'A':'(1)';
    'B':'(2)';
end_primitive;
primitive 'Q_CAP_C0603-22UF,6.3V,20%,X6S,A';body 'Q_CAP';
    'A':'(1)';
    'B':'(2)';
end_primitive;
primitive 'Q_CAP_C0603-4.7UF,25V,10%,X6S,A';body 'Q_CAP';
    'A':'(1)';
    'B':'(2)';
end_primitive;
primitive 'Q_CAP_C0805-10UF,25V,10%,X6S,CA';body 'Q_CAP';
    'A':'(1)';
    'B':'(2)';
end_primitive;
primitive 'Q_CAP_C0805-22UF,10V,20%,X6S,CA';body 'Q_CAP';
    'A':'(1)';
    'B':'(2)';
end_primitive;
primitive 'Q_CAP_C0805-22UF,16V,20%,X6S,CA';body 'Q_CAP';
    'A':'(1)';
    'B':'(2)';
end_primitive;
primitive 'Q_CAP_C1206-47UF,6.3V,20%,X6S,A';body 'Q_CAP';
    'A':'(1)';
    'B':'(2)';
end_primitive;
primitive 'Q_DIODE_SMLF-SDMK0340L-7-F,EMPA';body 'Q_DIODE';
    '1':'(1)';BIDI;
    '2':'(2)';BIDI;
end_primitive;
primitive 'Q_DIODE_SMLF-SDMK0340L-7-F,IC,A';body 'Q_DIODE';
    '1':'(1)';BIDI;
    '2':'(2)';BIDI;
end_primitive;
primitive 'Q_FUSE_SMLF-1.1A/8V,EMPTY,DK11A';body 'Q_FUSE';
    '1':'(1)';BIDI;
    '2':'(2)';BIDI;
end_primitive;
primitive 'Q_INDUCTOR4P_12-67/320MA,320MAA';body 'Q_INDUCTOR4P_12';
    '4':'(4)';BIDI;
    '3':'(3)';BIDI;
    '2':'(2)';BIDI;
    '1':'(1)';BIDI;
end_primitive;
primitive 'Q_INDUCTOR_SMLF-1UH,IND,CV-10BA';body 'Q_INDUCTOR';
    '2':'(2)';BIDI;
    '1':'(1)';BIDI;
end_primitive;
primitive 'Q_INDUCTOR_SMLF-3.3UH/6A,IND,CA';body 'Q_INDUCTOR';
    '2':'(2)';BIDI;
    '1':'(1)';BIDI;
end_primitive;
primitive 'Q_INDUCTOR_SMLF-4.7UH,IND,CV-4A';body 'Q_INDUCTOR';
    '2':'(2)';BIDI;
    '1':'(1)';BIDI;
end_primitive;
primitive 'Q_INDUCTOR_SMLF-BLM18BB470/500A';body 'Q_INDUCTOR';
    '2':'(2)';BIDI;
    '1':'(1)';BIDI;
end_primitive;
primitive 'Q_INDUCTOR_SMLF-BLM18EG121SN1DA';body 'Q_INDUCTOR';
    '2':'(2)';BIDI;
    '1':'(1)';BIDI;
end_primitive;
primitive 'Q_INDUCTOR_SMLF-BLM18PG121SN1DA';body 'Q_INDUCTOR';
    '2':'(2)';BIDI;
    '1':'(1)';BIDI;
end_primitive;
primitive 'Q_INDUCTOR_SMLF-BLM18PG121SN1DB';body 'Q_INDUCTOR';
    '2':'(2)';BIDI;
    '1':'(1)';BIDI;
end_primitive;
primitive 'Q_INDUCTOR_SMLF-BLM18SN220TN1DA';body 'Q_INDUCTOR';
    '2':'(2)';BIDI;
    '1':'(1)';BIDI;
end_primitive;
primitive 'Q_LED_SMLF-LED_BLUE,LTST-C281TA';body 'Q_LED';
    'A':'(A)';BIDI;
    'C':'(C)';BIDI;
end_primitive;
primitive 'Q_LED_SMLF-LED_GREEN,19-213/GVA';body 'Q_LED';
    'A':'(A)';BIDI;
    'C':'(C)';BIDI;
end_primitive;
primitive 'Q_LED_SMLF-LED_RED,19-217/R6C-A';body 'Q_LED';
    'A':'(A)';BIDI;
    'C':'(C)';BIDI;
end_primitive;
primitive 'Q_LED_THLF-LED_BLUE,HV-312470/A';body 'Q_LED';
    'A':'(A)';BIDI;
    'C':'(C)';BIDI;
end_primitive;
primitive 'Q_LED_THLF-LED_YELLOW,LTL-R42FA';body 'Q_LED';
    'A':'(A)';BIDI;
    'C':'(C)';BIDI;
end_primitive;
primitive 'Q_RES_0402LF-0,5%,1/16W,CHIP,CA';body 'Q_RES';
    'A':'(1)';
    'B':'(2)';
end_primitive;
primitive 'Q_RES_0402LF-0,5%,1/16W,EMPTY,A';body 'Q_RES';
    'A':'(1)';
    'B':'(2)';
end_primitive;
primitive 'Q_RES_0402LF-1.69K,1%,1/16W,CHA';body 'Q_RES';
    'A':'(1)';
    'B':'(2)';
end_primitive;
primitive 'Q_RES_0402LF-1.8K,1%,1/16W,CHIA';body 'Q_RES';
    'A':'(1)';
    'B':'(2)';
end_primitive;
primitive 'Q_RES_0402LF-10,1%,1/16W,CHIP,A';body 'Q_RES';
    'A':'(1)';
    'B':'(2)';
end_primitive;
primitive 'Q_RES_0402LF-100,1%,1/16W,CHIPA';body 'Q_RES';
    'A':'(1)';
    'B':'(2)';
end_primitive;
primitive 'Q_RES_0402LF-100,1%,1/16W,EMPTA';body 'Q_RES';
    'A':'(1)';
    'B':'(2)';
end_primitive;
primitive 'Q_RES_0402LF-100K,1%,1/16W,CHIA';body 'Q_RES';
    'A':'(1)';
    'B':'(2)';
end_primitive;
primitive 'Q_RES_0402LF-100K,1%,1/16W,EMPA';body 'Q_RES';
    'A':'(1)';
    'B':'(2)';
end_primitive;
primitive 'Q_RES_0402LF-10K,1%,1/16W,CHIPA';body 'Q_RES';
    'A':'(1)';
    'B':'(2)';
end_primitive;
primitive 'Q_RES_0402LF-10K,1%,1/16W,EMPTA';body 'Q_RES';
    'A':'(1)';
    'B':'(2)';
end_primitive;
primitive 'Q_RES_0402LF-10K,1%,1/16W,EMPTB';body 'Q_RES';
    'A':'(1)';
    'B':'(2)';
end_primitive;
primitive 'Q_RES_0402LF-110,1%,1/16W,CHIPA';body 'Q_RES';
    'A':'(1)';
    'B':'(2)';
end_primitive;
primitive 'Q_RES_0402LF-12.4K,1%,1/16W,CHA';body 'Q_RES';
    'A':'(1)';
    'B':'(2)';
end_primitive;
primitive 'Q_RES_0402LF-120,1%,1/16W,CHIPA';body 'Q_RES';
    'A':'(1)';
    'B':'(2)';
end_primitive;
primitive 'Q_RES_0402LF-120,1%,1/16W,EMPTA';body 'Q_RES';
    'A':'(1)';
    'B':'(2)';
end_primitive;
primitive 'Q_RES_0402LF-12K,1%,1/16W,CHIPA';body 'Q_RES';
    'A':'(1)';
    'B':'(2)';
end_primitive;
primitive 'Q_RES_0402LF-15.8K,1%,1/16W,CHA';body 'Q_RES';
    'A':'(1)';
    'B':'(2)';
end_primitive;
primitive 'Q_RES_0402LF-150,1%,1/16W,CHIPA';body 'Q_RES';
    'A':'(1)';
    'B':'(2)';
end_primitive;
primitive 'Q_RES_0402LF-150K,1%,1/16W,CHIA';body 'Q_RES';
    'A':'(1)';
    'B':'(2)';
end_primitive;
primitive 'Q_RES_0402LF-150K,1%,1/16W,EMPA';body 'Q_RES';
    'A':'(1)';
    'B':'(2)';
end_primitive;
primitive 'Q_RES_0402LF-15K,1%,1/16W,CHIPA';body 'Q_RES';
    'A':'(1)';
    'B':'(2)';
end_primitive;
primitive 'Q_RES_0402LF-16.9K,1%,1/16W,CHA';body 'Q_RES';
    'A':'(1)';
    'B':'(2)';
end_primitive;
primitive 'Q_RES_0402LF-1K,1%,1/16W,CHIP,A';body 'Q_RES';
    'A':'(1)';
    'B':'(2)';
end_primitive;
primitive 'Q_RES_0402LF-1K,1%,1/16W,EMPTYA';body 'Q_RES';
    'A':'(1)';
    'B':'(2)';
end_primitive;
primitive 'Q_RES_0402LF-1K,1%,1/16W,EMPTYB';body 'Q_RES';
    'A':'(1)';
    'B':'(2)';
end_primitive;
primitive 'Q_RES_0402LF-2.2,1%,1/16W,CHIPA';body 'Q_RES';
    'A':'(1)';
    'B':'(2)';
end_primitive;
primitive 'Q_RES_0402LF-2.21K,1%,1/16W,EMA';body 'Q_RES';
    'A':'(1)';
    'B':'(2)';
end_primitive;
primitive 'Q_RES_0402LF-2.2K,5%,1/16W,CHIA';body 'Q_RES';
    'A':'(1)';
    'B':'(2)';
end_primitive;
primitive 'Q_RES_0402LF-2.74K,1%,1/16W,CHA';body 'Q_RES';
    'A':'(1)';
    'B':'(2)';
end_primitive;
primitive 'Q_RES_0402LF-2.87K,1%,1/16W,CHA';body 'Q_RES';
    'A':'(1)';
    'B':'(2)';
end_primitive;
primitive 'Q_RES_0402LF-20.5K,1%,1/16W,CHA';body 'Q_RES';
    'A':'(1)';
    'B':'(2)';
end_primitive;
primitive 'Q_RES_0402LF-200,1%,1/16W,CHIPA';body 'Q_RES';
    'A':'(1)';
    'B':'(2)';
end_primitive;
primitive 'Q_RES_0402LF-200K,1%,1/16W,CHIA';body 'Q_RES';
    'A':'(1)';
    'B':'(2)';
end_primitive;
primitive 'Q_RES_0402LF-20K,1%,1/16W,CHIPA';body 'Q_RES';
    'A':'(1)';
    'B':'(2)';
end_primitive;
primitive 'Q_RES_0402LF-22,1%,1/16W,CHIP,A';body 'Q_RES';
    'A':'(1)';
    'B':'(2)';
end_primitive;
primitive 'Q_RES_0402LF-220,1%,1/16W,CHIPA';body 'Q_RES';
    'A':'(1)';
    'B':'(2)';
end_primitive;
primitive 'Q_RES_0402LF-240,1%,1/16W,CHIPA';body 'Q_RES';
    'A':'(1)';
    'B':'(2)';
end_primitive;
primitive 'Q_RES_0402LF-25.5K,1%,1/16W,CHA';body 'Q_RES';
    'A':'(1)';
    'B':'(2)';
end_primitive;
primitive 'Q_RES_0402LF-2K,1%,1/16W,CHIP,A';body 'Q_RES';
    'A':'(1)';
    'B':'(2)';
end_primitive;
primitive 'Q_RES_0402LF-2K,1%,1/16W,EMPTYA';body 'Q_RES';
    'A':'(1)';
    'B':'(2)';
end_primitive;
primitive 'Q_RES_0402LF-316,1%,1/16W,CHIPA';body 'Q_RES';
    'A':'(1)';
    'B':'(2)';
end_primitive;
primitive 'Q_RES_0402LF-33.2,1%,1/16W,CHIA';body 'Q_RES';
    'A':'(1)';
    'B':'(2)';
end_primitive;
primitive 'Q_RES_0402LF-33.2,1%,1/16W,EMPA';body 'Q_RES';
    'A':'(1)';
    'B':'(2)';
end_primitive;
primitive 'Q_RES_0402LF-330,1%,1/16W,CHIPA';body 'Q_RES';
    'A':'(1)';
    'B':'(2)';
end_primitive;
primitive 'Q_RES_0402LF-4.7K,1%,1/16W,CHIA';body 'Q_RES';
    'A':'(1)';
    'B':'(2)';
end_primitive;
primitive 'Q_RES_0402LF-4.7K,1%,1/16W,EMPA';body 'Q_RES';
    'A':'(1)';
    'B':'(2)';
end_primitive;
primitive 'Q_RES_0402LF-4.7K,1%,1/16W,EMPB';body 'Q_RES';
    'A':'(1)';
    'B':'(2)';
end_primitive;
primitive 'Q_RES_0402LF-40.2,1%,1/16W,CHIA';body 'Q_RES';
    'A':'(1)';
    'B':'(2)';
end_primitive;
primitive 'Q_RES_0402LF-402,1%,1/16W,CHIPA';body 'Q_RES';
    'A':'(1)';
    'B':'(2)';
end_primitive;
primitive 'Q_RES_0402LF-470K,1%,1/16W,CHIA';body 'Q_RES';
    'A':'(1)';
    'B':'(2)';
end_primitive;
primitive 'Q_RES_0402LF-47K,1%,1/16W,CHIPA';body 'Q_RES';
    'A':'(1)';
    'B':'(2)';
end_primitive;
primitive 'Q_RES_0402LF-49.9,1%,1/16W,CHIA';body 'Q_RES';
    'A':'(1)';
    'B':'(2)';
end_primitive;
primitive 'Q_RES_0402LF-49.9,1%,1/16W,EMPA';body 'Q_RES';
    'A':'(1)';
    'B':'(2)';
end_primitive;
primitive 'Q_RES_0402LF-49.9K,1%,1/16W,CHA';body 'Q_RES';
    'A':'(1)';
    'B':'(2)';
end_primitive;
primitive 'Q_RES_0402LF-499,1%,1/16W,CHIPA';body 'Q_RES';
    'A':'(1)';
    'B':'(2)';
end_primitive;
primitive 'Q_RES_0402LF-5.1,5%,1/16W,CHIPA';body 'Q_RES';
    'A':'(1)';
    'B':'(2)';
end_primitive;
primitive 'Q_RES_0402LF-5.36K,1%,1/16W,CHA';body 'Q_RES';
    'A':'(1)';
    'B':'(2)';
end_primitive;
primitive 'Q_RES_0402LF-5.49K,1%,1/16W,CHA';body 'Q_RES';
    'A':'(1)';
    'B':'(2)';
end_primitive;
primitive 'Q_RES_0402LF-56K,1%,1/16W,CHIPA';body 'Q_RES';
    'A':'(1)';
    'B':'(2)';
end_primitive;
primitive 'Q_RES_0402LF-60.4,1%,1/16W,CHIA';body 'Q_RES';
    'A':'(1)';
    'B':'(2)';
end_primitive;
primitive 'Q_RES_0402LF-60.4K,1%,1/16W,CHA';body 'Q_RES';
    'A':'(1)';
    'B':'(2)';
end_primitive;
primitive 'Q_RES_0402LF-665,1%,1/16W,CHIPA';body 'Q_RES';
    'A':'(1)';
    'B':'(2)';
end_primitive;
primitive 'Q_RES_0402LF-68.1,1%,1/16W,CHIA';body 'Q_RES';
    'A':'(1)';
    'B':'(2)';
end_primitive;
primitive 'Q_RES_0402LF-681K,1%,1/16W,CHIA';body 'Q_RES';
    'A':'(1)';
    'B':'(2)';
end_primitive;
primitive 'Q_RES_0402LF-75,1%,1/16W,CHIP,A';body 'Q_RES';
    'A':'(1)';
    'B':'(2)';
end_primitive;
primitive 'Q_RES_0402LF-750,1%,1/16W,CHIPA';body 'Q_RES';
    'A':'(1)';
    'B':'(2)';
end_primitive;
primitive 'Q_RES_0402LF-8.2K,5%,1/16W,CHIA';body 'Q_RES';
    'A':'(1)';
    'B':'(2)';
end_primitive;
primitive 'Q_RES_0402LF-8.2K,5%,1/16W,EMPA';body 'Q_RES';
    'A':'(1)';
    'B':'(2)';
end_primitive;
primitive 'Q_RES_0402LF-90.9,1%,1/16W,CHIA';body 'Q_RES';
    'A':'(1)';
    'B':'(2)';
end_primitive;
primitive 'Q_RES_0402LF-91K,1%,1/16W,CHIPA';body 'Q_RES';
    'A':'(1)';
    'B':'(2)';
end_primitive;
primitive 'Q_RES_0603LF-0,5%,1/10W,EMPTY,A';body 'Q_RES';
    'A':'(1)';
    'B':'(2)';
end_primitive;
primitive 'RT9059GQW-RT9059GQW,SMLF,IC,ALA';body 'RT9059GQW';
    'PGOOD':'(5)';OUT;
    'EN':'(6)';IN;
    'ADJ':'(4)';IN;
    'VOUT1':'(1)';OUT;
    'VIN1':'(7)';IN;
    'VDD':'(10)';IN;
    'EP':'(TH)';
    'VOUT2':'(2)';OUT;
    'VOUT3':'(3)';OUT;
    'VIN2':'(8)';IN;
    'VIN3':'(9)';IN;
end_primitive;
primitive 'SCHOTTKY_12-1N5819HW,SMLF,IC,BA';body 'SCHOTTKY_12';
    'A':'(1)';IN;
    'C':'(2)';BIDI;
end_primitive;
primitive 'SCHOTTKY_12-SBA130Q,SMLF,EMPTYA';body 'SCHOTTKY_12';
    'A':'(1)';IN;
    'C':'(2)';BIDI;
end_primitive;
primitive 'SCHOTTKY_AC-SS0530,SMLF,EMPTY,A';body 'SCHOTTKY_AC';
    'A':'(A)';IN;
    'C':'(C)';BIDI;
end_primitive;
primitive 'SCHOTTKY_AC-SS0530,SMLF,IC,BCSA';body 'SCHOTTKY_AC';
    'A':'(A)';IN;
    'C':'(C)';BIDI;
end_primitive;
primitive 'SCONN11_9192031111LF-SCONN11_9A';body 'SCONN11_9192031111LF';
    '1':'(1)';BIDI;
    '3':'(3)';BIDI;
    '4':'(4)';BIDI;
    '5':'(5)';BIDI;
    '2':'(2)';BIDI;
    'G1':'(G1)';
    'G2':'(G2)';
    '6':'(6)';BIDI;
    '7':'(7)';BIDI;
    '8':'(8)';BIDI;
    '9':'(9)';BIDI;
    '10':'(10)';BIDI;
    '11':'(11)';BIDI;
end_primitive;
primitive 'SCONN13_502280130CV01-SCONN13_A';body 'SCONN13_502280130CV01';
    '1':'(1)';BIDI;
    '2':'(2)';BIDI;
    '3':'(3)';BIDI;
    '4':'(4)';BIDI;
    '5':'(5)';BIDI;
    '6':'(6)';BIDI;
    '7':'(7)';BIDI;
    '8':'(8)';BIDI;
    '9':'(9)';BIDI;
    '10':'(10)';BIDI;
    '11':'(11)';BIDI;
    '12':'(12)';BIDI;
    '13':'(13)';BIDI;
    'G1':'(G1)';
    'G2':'(G2)';
end_primitive;
primitive 'SCONN16_ACASPI006P06-SCONN16_AA';body 'SCONN16_ACASPI006P06';
    'VCC':'(2)';
    'HOLD_N':'(1)';BIDI;
    'CS_N':'(7)';BIDI;
    'WP_N':'(9)';BIDI;
    'DI':'(15)';BIDI;
    'CLK':'(16)';BIDI;
    'GND':'(10)';
    'DO':'(8)';BIDI;
    'NC0':'(3)';BIDI;
    'NC1':'(4)';BIDI;
    'NC2':'(5)';BIDI;
    'NC3':'(6)';BIDI;
    'NC4':'(11)';BIDI;
    'NC6':'(12)';BIDI;
    'NC7':'(13)';BIDI;
    'NC8':'(14)';BIDI;
end_primitive;
primitive 'SCONN3_21291035BR2-SCONN3_212-A';body 'SCONN3_21291035BR2';
    '3':'(3)';BIDI;
    '2':'(2)';BIDI;
    '1':'(1)';BIDI;
end_primitive;
primitive 'SCONN3_212H9103GBR1-SCONN3_212A';body 'SCONN3_212H9103GBR1';
    '3':'(3)';BIDI;
    '2':'(2)';BIDI;
    '1':'(1)';BIDI;
end_primitive;
primitive 'SCONN3_212H9103GBR1-SCONN3_212B';body 'SCONN3_212H9103GBR1';
    '3':'(3)';BIDI;
    '2':'(2)';BIDI;
    '1':'(1)';BIDI;
end_primitive;
primitive 'SCONN67_NASA0S6730TS67-SCONN67A';body 'SCONN67_NASA0S6730TS67';
    '2':'(2)';BIDI;
    '4':'(4)';BIDI;
    '6':'(6)';BIDI;
    '16':'(16)';BIDI;
    '18':'(18)';BIDI;
    '20':'(20)';BIDI;
    '22':'(22)';BIDI;
    '24':'(24)';BIDI;
    '26':'(26)';BIDI;
    '28':'(28)';BIDI;
    '30':'(30)';BIDI;
    '32':'(32)';BIDI;
    '34':'(34)';BIDI;
    '36':'(36)';BIDI;
    '38':'(38)';BIDI;
    '40':'(40)';BIDI;
    '42':'(42)';BIDI;
    '44':'(44)';BIDI;
    '46':'(46)';BIDI;
    '48':'(48)';BIDI;
    '50':'(50)';BIDI;
    '52':'(52)';BIDI;
    '54':'(54)';BIDI;
    '56':'(56)';BIDI;
    '58':'(58)';BIDI;
    '60':'(60)';BIDI;
    '62':'(62)';BIDI;
    '64':'(64)';BIDI;
    '66':'(66)';BIDI;
    '68':'(68)';BIDI;
    '70':'(70)';BIDI;
    '72':'(72)';BIDI;
    '74':'(74)';BIDI;
    '1':'(1)';BIDI;
    '3':'(3)';BIDI;
    '5':'(5)';BIDI;
    '7':'(7)';BIDI;
    '17':'(17)';BIDI;
    '19':'(19)';BIDI;
    '21':'(21)';BIDI;
    '23':'(23)';BIDI;
    '25':'(25)';BIDI;
    '27':'(27)';BIDI;
    '29':'(29)';BIDI;
    '31':'(31)';BIDI;
    '33':'(33)';BIDI;
    '35':'(35)';BIDI;
    '37':'(37)';BIDI;
    '39':'(39)';BIDI;
    '41':'(41)';BIDI;
    '43':'(43)';BIDI;
    '45':'(45)';BIDI;
    '47':'(47)';BIDI;
    '49':'(49)';BIDI;
    '51':'(51)';BIDI;
    '53':'(53)';BIDI;
    '55':'(55)';BIDI;
    '57':'(57)';BIDI;
    '59':'(59)';BIDI;
    '61':'(61)';BIDI;
    '63':'(63)';BIDI;
    '65':'(65)';BIDI;
    '67':'(67)';BIDI;
    '69':'(69)';BIDI;
    '71':'(71)';BIDI;
    '73':'(73)';BIDI;
    '75':'(75)';BIDI;
    'G1':'(G1)';
    'G2':'(G2)';
end_primitive;
primitive 'SN74LVC1G07DCKR-SN74LVC1G07DCKA';body 'SN74LVC1G07DCKR';
    'VCC':'(5)';
    'A':'(2)';IN;
    'GND':'(3)';
    'Y':'(4)';OUT;
    'NC1':'(1)';OUT;
end_primitive;
primitive 'SN74LVC1G14DCKR_SMLF-IC,SN74LVA';body 'SN74LVC1G14DCKR';
    'A':'(2)';IN;
    'Y':'(4)';OUT;
    'NC':'(1)';OUT;
    'VCC':'(5)';
    'GND':'(3)';
end_primitive;
primitive 'SW_PUSHBUTTON4P_12_G34_H2-SW4SA';body 'SW_PUSHBUTTON4P_12_G34_H2';
    '1':'(1)';BIDI;
    '2':'(2)';BIDI;
    '3':'(3)';BIDI;
    '4':'(4)';BIDI;
end_primitive;
primitive 'TDR_3P_TH2-EMPTY,N_A';body 'TDR_3P';
    'GND':'(1)';
    'IO1':'(2)';
    'IO2':'(3)';
end_primitive;
primitive 'TPS3808G18DBVR-TPS3808G01DBVR,A';body 'TPS3808G18DBVR';
    '#RESET':'(1)';OUT;
    'GND':'(2)';
    '#MR':'(3)';IN;
    'VDD':'(6)';
    'CT':'(4)';IN;
    'SENSE':'(5)';
end_primitive;
primitive 'TP_TDR_4P_FTS_TH-TP_TDR_4P_DIPA';body 'TP_TDR_4P_FTS';
    'P1':'(2)';BIDI;
    'P2':'(3)';BIDI;
    'S1':'(1)';BIDI;
    'S2':'(4)';BIDI;
end_primitive;
END.
